(lib_symbols
	(symbol "antmicroCapacitors0402:C_100n_0402"
			(pin_numbers
				(hide yes)
			)
			(pin_names
				(hide yes)
			)
			(exclude_from_sim no)
			(in_bom yes)
			(on_board yes)
			(property "Reference" "C"
				(at 20.32 -5.08 0)
				(effects
					(font
						(size 1.27 1.27)
						(thickness 0.15)
					)
					(justify left bottom)
				)
			)
			(property "Value" "C_100n_0402"
				(at 20.32 -10.16 0)
				(effects
					(font
						(size 1.27 1.27)
						(thickness 0.15)
					)
					(justify left bottom)
					(hide yes)
				)
			)
			(property "Footprint" "antmicro-footprints:C_0402_1005Metric"
				(at 20.32 -12.7 0)
				(effects
					(font
						(size 1.27 1.27)
						(thickness 0.15)
					)
					(justify left bottom)
					(hide yes)
				)
			)
			(property "Datasheet" "https://www.murata.com/products/productdetail?partno=GRM155R61H104KE14%23"
				(at 20.32 -15.24 0)
				(effects
					(font
						(size 1.27 1.27)
						(thickness 0.15)
					)
					(justify left bottom)
					(hide yes)
				)
			)
			(property "Description" "SMD Multilayer Ceramic Capacitor, 0.1 µF, 50 V, 0402 [1005 Metric], ± 10%, X5R, GRM Series"
				(at 0 0 0)
				(effects
					(font
						(size 1.27 1.27)
					)
					(hide yes)
				)
			)
			(property "MPN" "GRM155R61H104KE14D"
				(at 20.32 -17.78 0)
				(effects
					(font
						(size 1.27 1.27)
						(thickness 0.15)
					)
					(justify left bottom)
					(hide yes)
				)
			)
			(property "Manufacturer" "Murata"
				(at 20.32 -20.32 0)
				(effects
					(font
						(size 1.27 1.27)
						(thickness 0.15)
					)
					(justify left bottom)
					(hide yes)
				)
			)
			(property "License" "Apache-2.0"
				(at 20.32 -22.86 0)
				(effects
					(font
						(size 1.27 1.27)
						(thickness 0.15)
					)
					(justify left bottom)
					(hide yes)
				)
			)
			(property "Author" "Antmicro"
				(at 20.32 -25.4 0)
				(effects
					(font
						(size 1.27 1.27)
						(thickness 0.15)
					)
					(justify left bottom)
					(hide yes)
				)
			)
			(property "Val" "100n"
				(at 20.32 -7.62 0)
				(effects
					(font
						(size 1.27 1.27)
						(thickness 0.15)
					)
					(justify left bottom)
				)
			)
			(property "Voltage" "50V"
				(at 20.32 -27.94 0)
				(effects
					(font
						(size 1.27 1.27)
					)
					(justify left bottom)
					(hide yes)
				)
			)
			(property "Dielectric" "X5R"
				(at 20.32 -30.48 0)
				(effects
					(font
						(size 1.27 1.27)
					)
					(justify left bottom)
					(hide yes)
				)
			)
			(property "ki_keywords" "0402, SMT, CAPACITOR, PASSIVE, CERAMIC, MLCC"
				(at 0 0 0)
				(effects
					(font
						(size 1.27 1.27)
					)
					(hide yes)
				)
			)
			(symbol "C_100n_0402_0_1"
				(polyline
					(pts
						(xy 2.032 -1.524) (xy 2.032 1.524)
					)
					(stroke
						(width 0.3048)
						(type default)
					)
					(fill
						(type none)
					)
				)
				(polyline
					(pts
						(xy 3.048 -1.524) (xy 3.048 1.524)
					)
					(stroke
						(width 0.3302)
						(type default)
					)
					(fill
						(type none)
					)
				)
			)
			(symbol "C_100n_0402_1_1"
				(pin passive line
					(at 0 0 0)
					(length 2.032)
					(name "~"
						(effects
							(font
								(size 1.27 1.27)
							)
						)
					)
					(number "1"
						(effects
							(font
								(size 1.27 1.27)
							)
						)
					)
				)
				(pin passive line
					(at 5.08 0 180)
					(length 2.032)
					(name "~"
						(effects
							(font
								(size 1.27 1.27)
							)
						)
					)
					(number "2"
						(effects
							(font
								(size 1.27 1.27)
							)
						)
					)
				)
			)
		)
	(symbol "antmicroCapacitors0402:C_1u_25V_0402"
			(pin_numbers
				(hide yes)
			)
			(pin_names
				(hide yes)
			)
			(exclude_from_sim no)
			(in_bom yes)
			(on_board yes)
			(property "Reference" "C"
				(at 20.32 -5.08 0)
				(effects
					(font
						(size 1.27 1.27)
						(thickness 0.15)
					)
					(justify left bottom)
				)
			)
			(property "Value" "C_1u_25V_0402"
				(at 20.32 -10.16 0)
				(effects
					(font
						(size 1.27 1.27)
						(thickness 0.15)
					)
					(justify left bottom)
					(hide yes)
				)
			)
			(property "Footprint" "antmicro-footprints:C_0402_1005Metric"
				(at 20.32 -12.7 0)
				(effects
					(font
						(size 1.27 1.27)
						(thickness 0.15)
					)
					(justify left bottom)
					(hide yes)
				)
			)
			(property "Datasheet" "https://www.murata.com/products/productdetail?partno=GRM155R61E105KE11%23"
				(at 20.32 -15.24 0)
				(effects
					(font
						(size 1.27 1.27)
						(thickness 0.15)
					)
					(justify left bottom)
					(hide yes)
				)
			)
			(property "Description" "SMD Multilayer Ceramic Capacitor, 1 µF, 25 V, 0402 [1005 Metric], ± 10%, X5R, GRM Series"
				(at 0 0 0)
				(effects
					(font
						(size 1.27 1.27)
					)
					(hide yes)
				)
			)
			(property "MPN" "GRM155R61E105KE11J"
				(at 20.32 -17.78 0)
				(effects
					(font
						(size 1.27 1.27)
						(thickness 0.15)
					)
					(justify left bottom)
					(hide yes)
				)
			)
			(property "Manufacturer" "Murata"
				(at 20.32 -20.32 0)
				(effects
					(font
						(size 1.27 1.27)
						(thickness 0.15)
					)
					(justify left bottom)
					(hide yes)
				)
			)
			(property "License" "Apache-2.0"
				(at 20.32 -22.86 0)
				(effects
					(font
						(size 1.27 1.27)
						(thickness 0.15)
					)
					(justify left bottom)
					(hide yes)
				)
			)
			(property "Author" "Antmicro"
				(at 20.32 -25.4 0)
				(effects
					(font
						(size 1.27 1.27)
						(thickness 0.15)
					)
					(justify left bottom)
					(hide yes)
				)
			)
			(property "Val" "1u"
				(at 20.32 -7.62 0)
				(effects
					(font
						(size 1.27 1.27)
						(thickness 0.15)
					)
					(justify left bottom)
				)
			)
			(property "Voltage" "25V"
				(at 20.32 -27.94 0)
				(effects
					(font
						(size 1.27 1.27)
					)
					(justify left bottom)
					(hide yes)
				)
			)
			(property "Dielectric" "X5R"
				(at 20.32 -30.48 0)
				(effects
					(font
						(size 1.27 1.27)
					)
					(justify left bottom)
					(hide yes)
				)
			)
			(property "ki_keywords" "0402, SMT, CAPACITOR, PASSIVE, CERAMIC"
				(at 0 0 0)
				(effects
					(font
						(size 1.27 1.27)
					)
					(hide yes)
				)
			)
			(symbol "C_1u_25V_0402_0_1"
				(polyline
					(pts
						(xy 2.032 -1.524) (xy 2.032 1.524)
					)
					(stroke
						(width 0.3048)
						(type default)
					)
					(fill
						(type none)
					)
				)
				(polyline
					(pts
						(xy 3.048 -1.524) (xy 3.048 1.524)
					)
					(stroke
						(width 0.3302)
						(type default)
					)
					(fill
						(type none)
					)
				)
			)
			(symbol "C_1u_25V_0402_1_1"
				(pin passive line
					(at 0 0 0)
					(length 2.032)
					(name "~"
						(effects
							(font
								(size 1.27 1.27)
							)
						)
					)
					(number "1"
						(effects
							(font
								(size 1.27 1.27)
							)
						)
					)
				)
				(pin passive line
					(at 5.08 0 180)
					(length 2.032)
					(name "~"
						(effects
							(font
								(size 1.27 1.27)
							)
						)
					)
					(number "2"
						(effects
							(font
								(size 1.27 1.27)
							)
						)
					)
				)
			)
		)
	(symbol "antmicroCapacitors0402:C_33n_0402"
			(pin_numbers
				(hide yes)
			)
			(pin_names
				(hide yes)
			)
			(exclude_from_sim no)
			(in_bom yes)
			(on_board yes)
			(property "Reference" "C"
				(at 20.32 -5.08 0)
				(effects
					(font
						(size 1.27 1.27)
						(thickness 0.15)
					)
					(justify left bottom)
				)
			)
			(property "Value" "C_33n_0402"
				(at 20.32 -10.16 0)
				(effects
					(font
						(size 1.27 1.27)
						(thickness 0.15)
					)
					(justify left bottom)
					(hide yes)
				)
			)
			(property "Footprint" "antmicro-footprints:C_0402_1005Metric"
				(at 20.32 -12.7 0)
				(effects
					(font
						(size 1.27 1.27)
						(thickness 0.15)
					)
					(justify left bottom)
					(hide yes)
				)
			)
			(property "Datasheet" "https://www.murata.com/products/productdetail?partno=GCM155R71E333KA55%23"
				(at 20.32 -15.24 0)
				(effects
					(font
						(size 1.27 1.27)
						(thickness 0.15)
					)
					(justify left bottom)
					(hide yes)
				)
			)
			(property "Description" "SMD Multilayer Ceramic Capacitor, 33000 pF, 25 V, 0402 [1005 Metric], ± 10%, X7R, MC"
				(at 0 0 0)
				(effects
					(font
						(size 1.27 1.27)
					)
					(hide yes)
				)
			)
			(property "MPN" "GCM155R71E333KA55D"
				(at 20.32 -17.78 0)
				(effects
					(font
						(size 1.27 1.27)
						(thickness 0.15)
					)
					(justify left bottom)
					(hide yes)
				)
			)
			(property "Manufacturer" "Murata"
				(at 20.32 -20.32 0)
				(effects
					(font
						(size 1.27 1.27)
						(thickness 0.15)
					)
					(justify left bottom)
					(hide yes)
				)
			)
			(property "License" "Apache-2.0"
				(at 20.32 -22.86 0)
				(effects
					(font
						(size 1.27 1.27)
						(thickness 0.15)
					)
					(justify left bottom)
					(hide yes)
				)
			)
			(property "Author" "Antmicro"
				(at 20.32 -25.4 0)
				(effects
					(font
						(size 1.27 1.27)
						(thickness 0.15)
					)
					(justify left bottom)
					(hide yes)
				)
			)
			(property "Val" "33n"
				(at 20.32 -7.62 0)
				(effects
					(font
						(size 1.27 1.27)
						(thickness 0.15)
					)
					(justify left bottom)
				)
			)
			(property "Voltage" ""
				(at 20.32 -27.94 0)
				(effects
					(font
						(size 1.27 1.27)
					)
					(justify left bottom)
					(hide yes)
				)
			)
			(property "Dielectric" ""
				(at 20.32 -30.48 0)
				(effects
					(font
						(size 1.27 1.27)
					)
					(justify left bottom)
					(hide yes)
				)
			)
			(property "ki_keywords" "0402, SMT, CAPACITOR, PASSIVE"
				(at 0 0 0)
				(effects
					(font
						(size 1.27 1.27)
					)
					(hide yes)
				)
			)
			(symbol "C_33n_0402_0_1"
				(polyline
					(pts
						(xy 2.032 -1.524) (xy 2.032 1.524)
					)
					(stroke
						(width 0.3048)
						(type default)
					)
					(fill
						(type none)
					)
				)
				(polyline
					(pts
						(xy 3.048 -1.524) (xy 3.048 1.524)
					)
					(stroke
						(width 0.3302)
						(type default)
					)
					(fill
						(type none)
					)
				)
			)
			(symbol "C_33n_0402_1_1"
				(pin passive line
					(at 0 0 0)
					(length 2.032)
					(name "~"
						(effects
							(font
								(size 1.27 1.27)
							)
						)
					)
					(number "1"
						(effects
							(font
								(size 1.27 1.27)
							)
						)
					)
				)
				(pin passive line
					(at 5.08 0 180)
					(length 2.032)
					(name "~"
						(effects
							(font
								(size 1.27 1.27)
							)
						)
					)
					(number "2"
						(effects
							(font
								(size 1.27 1.27)
							)
						)
					)
				)
			)
		)
	(symbol "antmicroCapacitors0402:C_4u7_25V_0402"
			(pin_numbers
				(hide yes)
			)
			(pin_names
				(hide yes)
			)
			(exclude_from_sim no)
			(in_bom yes)
			(on_board yes)
			(property "Reference" "C"
				(at 20.32 -5.08 0)
				(effects
					(font
						(size 1.27 1.27)
						(thickness 0.15)
					)
					(justify left bottom)
				)
			)
			(property "Value" "C_4u7_25V_0402"
				(at 20.32 -10.16 0)
				(effects
					(font
						(size 1.27 1.27)
						(thickness 0.15)
					)
					(justify left bottom)
					(hide yes)
				)
			)
			(property "Footprint" "antmicro-footprints:C_0402_1005Metric"
				(at 20.32 -12.7 0)
				(effects
					(font
						(size 1.27 1.27)
						(thickness 0.15)
					)
					(justify left bottom)
					(hide yes)
				)
			)
			(property "Datasheet" "https://www.murata.com/products/productdetail?partno=GRM155C61E475ME15%23"
				(at 20.32 -15.24 0)
				(effects
					(font
						(size 1.27 1.27)
						(thickness 0.15)
					)
					(justify left bottom)
					(hide yes)
				)
			)
			(property "Description" "SMD Multilayer Ceramic Capacitor"
				(at 0 0 0)
				(effects
					(font
						(size 1.27 1.27)
					)
					(hide yes)
				)
			)
			(property "MPN" "GRM155C61E475ME15J"
				(at 20.32 -17.78 0)
				(effects
					(font
						(size 1.27 1.27)
						(thickness 0.15)
					)
					(justify left bottom)
					(hide yes)
				)
			)
			(property "Manufacturer" "Murata"
				(at 20.32 -20.32 0)
				(effects
					(font
						(size 1.27 1.27)
						(thickness 0.15)
					)
					(justify left bottom)
					(hide yes)
				)
			)
			(property "License" "Apache-2.0"
				(at 20.32 -22.86 0)
				(effects
					(font
						(size 1.27 1.27)
						(thickness 0.15)
					)
					(justify left bottom)
					(hide yes)
				)
			)
			(property "Author" "Antmicro"
				(at 20.32 -25.4 0)
				(effects
					(font
						(size 1.27 1.27)
						(thickness 0.15)
					)
					(justify left bottom)
					(hide yes)
				)
			)
			(property "Val" "4u7"
				(at 20.32 -7.62 0)
				(effects
					(font
						(size 1.27 1.27)
						(thickness 0.15)
					)
					(justify left bottom)
				)
			)
			(property "Voltage" "25V"
				(at 20.32 -27.94 0)
				(effects
					(font
						(size 1.27 1.27)
					)
					(justify left bottom)
					(hide yes)
				)
			)
			(property "Dielectric" "X5S"
				(at 20.32 -30.48 0)
				(effects
					(font
						(size 1.27 1.27)
					)
					(justify left bottom)
					(hide yes)
				)
			)
			(property "ki_keywords" "0402, SMT, CAPACITOR, PASSIVE, CERAMIC"
				(at 0 0 0)
				(effects
					(font
						(size 1.27 1.27)
					)
					(hide yes)
				)
			)
			(symbol "C_4u7_25V_0402_0_1"
				(polyline
					(pts
						(xy 2.032 -1.524) (xy 2.032 1.524)
					)
					(stroke
						(width 0.3048)
						(type default)
					)
					(fill
						(type none)
					)
				)
				(polyline
					(pts
						(xy 3.048 -1.524) (xy 3.048 1.524)
					)
					(stroke
						(width 0.3302)
						(type default)
					)
					(fill
						(type none)
					)
				)
			)
			(symbol "C_4u7_25V_0402_1_1"
				(pin passive line
					(at 0 0 0)
					(length 2.032)
					(name "~"
						(effects
							(font
								(size 1.27 1.27)
							)
						)
					)
					(number "1"
						(effects
							(font
								(size 1.27 1.27)
							)
						)
					)
				)
				(pin passive line
					(at 5.08 0 180)
					(length 2.032)
					(name "~"
						(effects
							(font
								(size 1.27 1.27)
							)
						)
					)
					(number "2"
						(effects
							(font
								(size 1.27 1.27)
							)
						)
					)
				)
			)
		)
	(symbol "antmicroCapacitorsmisc:C_10u_0805_35V"
			(pin_numbers
				(hide yes)
			)
			(pin_names
				(hide yes)
			)
			(exclude_from_sim no)
			(in_bom yes)
			(on_board yes)
			(property "Reference" "C"
				(at 20.32 -5.08 0)
				(effects
					(font
						(size 1.27 1.27)
						(thickness 0.15)
					)
					(justify left bottom)
				)
			)
			(property "Value" "C_10u_0805_35V"
				(at 20.32 -10.16 0)
				(effects
					(font
						(size 1.27 1.27)
						(thickness 0.15)
					)
					(justify left bottom)
					(hide yes)
				)
			)
			(property "Footprint" "antmicro-footprints:C_0805_2012Metric"
				(at 20.32 -12.7 0)
				(effects
					(font
						(size 1.27 1.27)
						(thickness 0.15)
					)
					(justify left bottom)
					(hide yes)
				)
			)
			(property "Datasheet" "https://www.murata.com/products/productdetail?partno=GRM21BR6YA106KE43%23"
				(at 20.32 -15.24 0)
				(effects
					(font
						(size 1.27 1.27)
						(thickness 0.15)
					)
					(justify left bottom)
					(hide yes)
				)
			)
			(property "Description" "SMD Multilayer Ceramic Capacitor, 10 µF, 35 V, 0805 [2012 Metric], ± 10%, X5R, GRM Series"
				(at 0 0 0)
				(effects
					(font
						(size 1.27 1.27)
					)
					(hide yes)
				)
			)
			(property "MPN" "GRM21BR6YA106KE43L"
				(at 20.32 -17.78 0)
				(effects
					(font
						(size 1.27 1.27)
						(thickness 0.15)
					)
					(justify left bottom)
					(hide yes)
				)
			)
			(property "Manufacturer" "Murata"
				(at 20.32 -20.32 0)
				(effects
					(font
						(size 1.27 1.27)
						(thickness 0.15)
					)
					(justify left bottom)
					(hide yes)
				)
			)
			(property "License" "Apache-2.0"
				(at 20.32 -22.86 0)
				(effects
					(font
						(size 1.27 1.27)
						(thickness 0.15)
					)
					(justify left bottom)
					(hide yes)
				)
			)
			(property "Author" "Antmicro"
				(at 20.32 -25.4 0)
				(effects
					(font
						(size 1.27 1.27)
						(thickness 0.15)
					)
					(justify left bottom)
					(hide yes)
				)
			)
			(property "Val" "10u"
				(at 20.32 -7.62 0)
				(effects
					(font
						(size 1.27 1.27)
						(thickness 0.15)
					)
					(justify left bottom)
				)
			)
			(property "Voltage" "35V"
				(at 20.32 -27.94 0)
				(effects
					(font
						(size 1.27 1.27)
					)
					(justify left bottom)
					(hide yes)
				)
			)
			(property "Dielectric" ""
				(at 20.32 -30.48 0)
				(effects
					(font
						(size 1.27 1.27)
					)
					(justify left bottom)
					(hide yes)
				)
			)
			(property "Public" "False"
				(at 20.32 -33.02 0)
				(effects
					(font
						(size 1.27 1.27)
					)
					(justify left bottom)
					(hide yes)
				)
			)
			(property "ki_keywords" "0805, SMT, CAPACITOR, PASSIVE"
				(at 0 0 0)
				(effects
					(font
						(size 1.27 1.27)
					)
					(hide yes)
				)
			)
			(symbol "C_10u_0805_35V_0_1"
				(polyline
					(pts
						(xy 2.032 -1.524) (xy 2.032 1.524)
					)
					(stroke
						(width 0.3048)
						(type default)
					)
					(fill
						(type none)
					)
				)
				(polyline
					(pts
						(xy 3.048 -1.524) (xy 3.048 1.524)
					)
					(stroke
						(width 0.3302)
						(type default)
					)
					(fill
						(type none)
					)
				)
			)
			(symbol "C_10u_0805_35V_1_1"
				(pin passive line
					(at 0 0 0)
					(length 2.032)
					(name "~"
						(effects
							(font
								(size 1.27 1.27)
							)
						)
					)
					(number "1"
						(effects
							(font
								(size 1.27 1.27)
							)
						)
					)
				)
				(pin passive line
					(at 5.08 0 180)
					(length 2.032)
					(name "~"
						(effects
							(font
								(size 1.27 1.27)
							)
						)
					)
					(number "2"
						(effects
							(font
								(size 1.27 1.27)
							)
						)
					)
				)
			)
		)
	(symbol "antmicroCapacitorsmisc:C_22u_25V_0805"
			(pin_numbers
				(hide yes)
			)
			(pin_names
				(hide yes)
			)
			(exclude_from_sim no)
			(in_bom yes)
			(on_board yes)
			(property "Reference" "C"
				(at 20.32 -5.08 0)
				(effects
					(font
						(size 1.27 1.27)
						(thickness 0.15)
					)
					(justify left bottom)
				)
			)
			(property "Value" "C_22u_25V_0805"
				(at 20.32 -10.16 0)
				(effects
					(font
						(size 1.27 1.27)
						(thickness 0.15)
					)
					(justify left bottom)
					(hide yes)
				)
			)
			(property "Footprint" "antmicro-footprints:C_0805_2012Metric"
				(at 20.32 -12.7 0)
				(effects
					(font
						(size 1.27 1.27)
						(thickness 0.15)
					)
					(justify left bottom)
					(hide yes)
				)
			)
			(property "Datasheet" "https://product.samsungsem.com/mlcc/CL21A226MAYNNN.do"
				(at 20.32 -15.24 0)
				(effects
					(font
						(size 1.27 1.27)
						(thickness 0.15)
					)
					(justify left bottom)
					(hide yes)
				)
			)
			(property "Description" "SMT Multilayer Ceramic Capacitor, 22uF, +/-20%, 25V, X5R, 0805 [2012 Metric]"
				(at 0 0 0)
				(effects
					(font
						(size 1.27 1.27)
					)
					(hide yes)
				)
			)
			(property "MPN" "CL21A226MAYNNNE"
				(at 20.32 -17.78 0)
				(effects
					(font
						(size 1.27 1.27)
						(thickness 0.15)
					)
					(justify left bottom)
					(hide yes)
				)
			)
			(property "Manufacturer" "Samsung Electro-Mechanics"
				(at 20.32 -20.32 0)
				(effects
					(font
						(size 1.27 1.27)
						(thickness 0.15)
					)
					(justify left bottom)
					(hide yes)
				)
			)
			(property "License" "Apache-2.0"
				(at 20.32 -22.86 0)
				(effects
					(font
						(size 1.27 1.27)
						(thickness 0.15)
					)
					(justify left bottom)
					(hide yes)
				)
			)
			(property "Author" "Antmicro"
				(at 20.32 -25.4 0)
				(effects
					(font
						(size 1.27 1.27)
						(thickness 0.15)
					)
					(justify left bottom)
					(hide yes)
				)
			)
			(property "Val" "22u"
				(at 20.32 -7.62 0)
				(effects
					(font
						(size 1.27 1.27)
						(thickness 0.15)
					)
					(justify left bottom)
				)
			)
			(property "Voltage" "25V"
				(at 20.32 -27.94 0)
				(effects
					(font
						(size 1.27 1.27)
					)
					(justify left bottom)
				)
			)
			(property "Dielectric" "X5R"
				(at 20.32 -30.48 0)
				(effects
					(font
						(size 1.27 1.27)
					)
					(justify left bottom)
					(hide yes)
				)
			)
			(property "Public" "False"
				(at 20.32 -33.02 0)
				(effects
					(font
						(size 1.27 1.27)
					)
					(justify left bottom)
					(hide yes)
				)
			)
			(property "ki_keywords" "0805, SMT, CAPACITOR, PASSIVE"
				(at 0 0 0)
				(effects
					(font
						(size 1.27 1.27)
					)
					(hide yes)
				)
			)
			(symbol "C_22u_25V_0805_0_1"
				(polyline
					(pts
						(xy 2.032 -1.524) (xy 2.032 1.524)
					)
					(stroke
						(width 0.3048)
						(type default)
					)
					(fill
						(type none)
					)
				)
				(polyline
					(pts
						(xy 3.048 -1.524) (xy 3.048 1.524)
					)
					(stroke
						(width 0.3302)
						(type default)
					)
					(fill
						(type none)
					)
				)
			)
			(symbol "C_22u_25V_0805_1_1"
				(pin passive line
					(at 0 0 0)
					(length 2.032)
					(name "~"
						(effects
							(font
								(size 1.27 1.27)
							)
						)
					)
					(number "1"
						(effects
							(font
								(size 1.27 1.27)
							)
						)
					)
				)
				(pin passive line
					(at 5.08 0 180)
					(length 2.032)
					(name "~"
						(effects
							(font
								(size 1.27 1.27)
							)
						)
					)
					(number "2"
						(effects
							(font
								(size 1.27 1.27)
							)
						)
					)
				)
			)
		)
	(symbol "antmicroCapacitorspol:C_Pol_100u_10V_KEMET-T520-B"
			(pin_numbers
				(hide yes)
			)
			(pin_names
				(hide yes)
			)
			(exclude_from_sim no)
			(in_bom yes)
			(on_board yes)
			(property "Reference" "C"
				(at 13.97 0 0)
				(effects
					(font
						(size 1.27 1.27)
						(thickness 0.15)
					)
					(justify left bottom)
				)
			)
			(property "Value" "C_Pol_100u_10V_KEMET-T520-B"
				(at 13.97 -2.54 0)
				(effects
					(font
						(size 1.27 1.27)
						(thickness 0.15)
					)
					(justify left bottom)
					(hide yes)
				)
			)
			(property "Footprint" "antmicro-footprints:C_Pol_EIA-B"
				(at 13.97 -7.62 0)
				(effects
					(font
						(size 1.27 1.27)
						(thickness 0.15)
					)
					(justify left bottom)
					(hide yes)
				)
			)
			(property "Datasheet" "https://www.kemet.com/en/us/capacitors/product/T520B107M010ATE070.html"
				(at 13.97 -10.16 0)
				(effects
					(font
						(size 1.27 1.27)
						(thickness 0.15)
					)
					(justify left bottom)
					(hide yes)
				)
			)
			(property "Description" "Tantalum Capacitors - Polymer 10V 100uF 1311 20% ESR=70mOhms"
				(at 0 0 0)
				(effects
					(font
						(size 1.27 1.27)
					)
					(hide yes)
				)
			)
			(property "Val" "100u"
				(at 13.97 -5.08 0)
				(effects
					(font
						(size 1.27 1.27)
						(thickness 0.15)
					)
					(justify left bottom)
				)
			)
			(property "MPN" "T520B107M010ATE070"
				(at 13.97 -12.7 0)
				(effects
					(font
						(size 1.27 1.27)
						(thickness 0.15)
					)
					(justify left bottom)
					(hide yes)
				)
			)
			(property "Manufacturer" "KEMET"
				(at 13.97 -15.24 0)
				(effects
					(font
						(size 1.27 1.27)
						(thickness 0.15)
					)
					(justify left bottom)
					(hide yes)
				)
			)
			(property "License" "Apache-2.0"
				(at 13.97 -17.78 0)
				(effects
					(font
						(size 1.27 1.27)
						(thickness 0.15)
					)
					(justify left bottom)
					(hide yes)
				)
			)
			(property "Author" "Antmicro"
				(at 13.97 -20.32 0)
				(effects
					(font
						(size 1.27 1.27)
						(thickness 0.15)
					)
					(justify left bottom)
					(hide yes)
				)
			)
			(property "Voltage" "10V"
				(at 13.97 -22.86 0)
				(effects
					(font
						(size 1.27 1.27)
					)
					(justify left bottom)
				)
			)
			(property "Dielectric" "template_dielectric"
				(at 13.97 -25.4 0)
				(effects
					(font
						(size 1.27 1.27)
					)
					(justify left bottom)
					(hide yes)
				)
			)
			(property "ki_keywords" "SMT, CAPACITOR, PASSIVE, POLARIZED, TANTALUM"
				(at 0 0 0)
				(effects
					(font
						(size 1.27 1.27)
					)
					(hide yes)
				)
			)
			(symbol "C_Pol_100u_10V_KEMET-T520-B_0_1"
				(polyline
					(pts
						(xy 0.9652 1.27) (xy 0.9652 1.778)
					)
					(stroke
						(width 0)
						(type default)
					)
					(fill
						(type none)
					)
				)
				(polyline
					(pts
						(xy 1.2192 1.524) (xy 0.7112 1.524)
					)
					(stroke
						(width 0)
						(type default)
					)
					(fill
						(type none)
					)
				)
				(rectangle
					(start 1.905 -1.524)
					(end 2.286 1.524)
					(stroke
						(width 0)
						(type default)
					)
					(fill
						(type none)
					)
				)
				(rectangle
					(start 2.921 -1.524)
					(end 3.302 1.524)
					(stroke
						(width 0)
						(type default)
					)
					(fill
						(type outline)
					)
				)
			)
			(symbol "C_Pol_100u_10V_KEMET-T520-B_1_1"
				(pin passive line
					(at 0 0 0)
					(length 1.8542)
					(name "~"
						(effects
							(font
								(size 1.27 1.27)
							)
						)
					)
					(number "1"
						(effects
							(font
								(size 1.27 1.27)
							)
						)
					)
				)
				(pin passive line
					(at 5.08 0 180)
					(length 1.8542)
					(name "~"
						(effects
							(font
								(size 1.27 1.27)
							)
						)
					)
					(number "2"
						(effects
							(font
								(size 1.27 1.27)
							)
						)
					)
				)
			)
		)
	(symbol "antmicroCapacitorspol:C_Pol_150u_30V_Vishay-T59-EE"
			(pin_numbers
				(hide yes)
			)
			(pin_names
				(hide yes)
			)
			(exclude_from_sim no)
			(in_bom yes)
			(on_board yes)
			(property "Reference" "C"
				(at 15.24 -5.08 0)
				(effects
					(font
						(size 1.27 1.27)
						(thickness 0.15)
					)
					(justify left bottom)
				)
			)
			(property "Value" "C_Pol_150u_30V_Vishay-T59-EE"
				(at 15.24 -10.16 0)
				(effects
					(font
						(size 1.27 1.27)
						(thickness 0.15)
					)
					(justify left bottom)
					(hide yes)
				)
			)
			(property "Footprint" "antmicro-footprints:C_Pol_Vishay-T59-EE"
				(at 15.24 -12.7 0)
				(effects
					(font
						(size 1.27 1.27)
						(thickness 0.15)
					)
					(justify left bottom)
					(hide yes)
				)
			)
			(property "Datasheet" "https://www.vishay.com/docs/40191/t59.pdf"
				(at 15.24 -15.24 0)
				(effects
					(font
						(size 1.27 1.27)
						(thickness 0.15)
					)
					(justify left bottom)
					(hide yes)
				)
			)
			(property "Description" "Tantalum Capacitors - Polymer 150uF 30volts 20% 75mohms maxESR"
				(at 0 0 0)
				(effects
					(font
						(size 1.27 1.27)
					)
					(hide yes)
				)
			)
			(property "Manufacturer" "Vishay"
				(at 15.24 -17.78 0)
				(effects
					(font
						(size 1.27 1.27)
						(thickness 0.15)
					)
					(justify left bottom)
					(hide yes)
				)
			)
			(property "MPN" "T59EE157M030C0075"
				(at 15.24 -27.94 0)
				(effects
					(font
						(size 1.27 1.27)
					)
					(justify left bottom)
					(hide yes)
				)
			)
			(property "Voltage" "30V"
				(at 15.24 -20.32 0)
				(effects
					(font
						(size 1.27 1.27)
						(thickness 0.15)
					)
					(justify left bottom)
					(hide yes)
				)
			)
			(property "Val" "150u"
				(at 15.24 -7.62 0)
				(effects
					(font
						(size 1.27 1.27)
						(thickness 0.15)
					)
					(justify left bottom)
				)
			)
			(property "Author" "Antmicro"
				(at 15.24 -22.86 0)
				(effects
					(font
						(size 1.27 1.27)
						(thickness 0.15)
					)
					(justify left bottom)
					(hide yes)
				)
			)
			(property "License" "Apache-2.0"
				(at 15.24 -25.4 0)
				(effects
					(font
						(size 1.27 1.27)
						(thickness 0.15)
					)
					(justify left bottom)
					(hide yes)
				)
			)
			(property "Dielectric" "template_dielectric"
				(at 13.97 -25.4 0)
				(effects
					(font
						(size 1.27 1.27)
					)
					(justify left bottom)
					(hide yes)
				)
			)
			(property "ki_keywords" "SMT, CAPACITOR, PASSIVE, POLARIZED, TANTALUM"
				(at 0 0 0)
				(effects
					(font
						(size 1.27 1.27)
					)
					(hide yes)
				)
			)
			(symbol "C_Pol_150u_30V_Vishay-T59-EE_0_1"
				(polyline
					(pts
						(xy 0.9652 1.27) (xy 0.9652 1.778)
					)
					(stroke
						(width 0)
						(type default)
					)
					(fill
						(type none)
					)
				)
				(polyline
					(pts
						(xy 1.2192 1.524) (xy 0.7112 1.524)
					)
					(stroke
						(width 0)
						(type default)
					)
					(fill
						(type none)
					)
				)
				(rectangle
					(start 1.905 -1.524)
					(end 2.286 1.524)
					(stroke
						(width 0)
						(type default)
					)
					(fill
						(type none)
					)
				)
				(rectangle
					(start 2.921 -1.524)
					(end 3.302 1.524)
					(stroke
						(width 0)
						(type default)
					)
					(fill
						(type outline)
					)
				)
			)
			(symbol "C_Pol_150u_30V_Vishay-T59-EE_1_1"
				(pin passive line
					(at 0 0 0)
					(length 1.8542)
					(name "~"
						(effects
							(font
								(size 1.27 1.27)
							)
						)
					)
					(number "1"
						(effects
							(font
								(size 1.27 1.27)
							)
						)
					)
				)
				(pin passive line
					(at 5.08 0 180)
					(length 1.8542)
					(name "~"
						(effects
							(font
								(size 1.27 1.27)
							)
						)
					)
					(number "2"
						(effects
							(font
								(size 1.27 1.27)
							)
						)
					)
				)
			)
		)
	(symbol "antmicroClockTimingRealTimeClocks:DSC557-0343FI1"
			(exclude_from_sim no)
			(in_bom yes)
			(on_board yes)
			(property "Reference" "U"
				(at 45.72 -7.62 0)
				(effects
					(font
						(size 1.27 1.27)
						(thickness 0.15)
					)
					(justify left bottom)
				)
			)
			(property "Value" "DSC557-0343FI1"
				(at 45.72 -10.16 0)
				(effects
					(font
						(size 1.27 1.27)
						(thickness 0.15)
					)
					(justify left bottom)
					(hide yes)
				)
			)
			(property "Footprint" "antmicro-footprints:VQFN-14-1EP_3.2x2.5mm_P0.5mm_Layout4x3"
				(at 45.72 -15.24 0)
				(effects
					(font
						(size 1.27 1.27)
						(thickness 0.15)
					)
					(justify left bottom)
					(hide yes)
				)
			)
			(property "Datasheet" "https://ww1.microchip.com/downloads/aemDocuments/documents/TCG/ProductDocuments/DataSheets/DSC557-03-04-05-Multiple-Output-MEMS-PCIe-Gen1-2-3-4-Clock-Generators-DS20006691.pdf"
				(at 45.72 -20.32 0)
				(effects
					(font
						(size 1.27 1.27)
						(thickness 0.15)
					)
					(justify left bottom)
					(hide yes)
				)
			)
			(property "Description" "Two output PCIe Clock Generator"
				(at 61.722 -29.464 0)
				(effects
					(font
						(size 1.27 1.27)
					)
					(hide yes)
				)
			)
			(property "Manufacturer" "Microchip Technology"
				(at 45.72 -22.86 0)
				(effects
					(font
						(size 1.27 1.27)
						(thickness 0.15)
					)
					(justify left bottom)
					(hide yes)
				)
			)
			(property "MPN" "DSC557-0343FI1"
				(at 45.72 -17.78 0)
				(effects
					(font
						(size 1.27 1.27)
						(thickness 0.15)
					)
					(justify left bottom)
				)
			)
			(property "Val" "100 MHz"
				(at 45.72 -12.7 0)
				(effects
					(font
						(size 1.27 1.27)
					)
					(justify left bottom)
				)
			)
			(property "Author" "Antmicro"
				(at 45.72 -25.4 0)
				(effects
					(font
						(size 1.27 1.27)
						(thickness 0.15)
					)
					(justify left bottom)
					(hide yes)
				)
			)
			(property "License" "Apache-2.0"
				(at 45.72 -27.94 0)
				(effects
					(font
						(size 1.27 1.27)
						(thickness 0.15)
					)
					(justify left bottom)
					(hide yes)
				)
			)
			(property "ki_keywords" "SMT, IC, CLOCK, PCIE"
				(at 0 0 0)
				(effects
					(font
						(size 1.27 1.27)
					)
					(hide yes)
				)
			)
			(symbol "DSC557-0343FI1_0_1"
				(polyline
					(pts
						(xy 24.13 0) (xy 16.51 0) (xy 16.51 -5.08) (xy 24.13 -5.08)
					)
					(stroke
						(width 0)
						(type default)
					)
					(fill
						(type none)
					)
				)
				(polyline
					(pts
						(xy 24.13 -7.62) (xy 16.51 -7.62) (xy 16.51 -12.7) (xy 24.13 -12.7)
					)
					(stroke
						(width 0)
						(type default)
					)
					(fill
						(type none)
					)
				)
			)
			(symbol "DSC557-0343FI1_1_1"
				(rectangle
					(start 2.54 2.54)
					(end 24.13 -15.24)
					(stroke
						(width 0.254)
						(type default)
					)
					(fill
						(type background)
					)
				)
				(polyline
					(pts
						(xy 15.24 -2.54) (xy 16.51 -2.54)
					)
					(stroke
						(width 0)
						(type default)
					)
					(fill
						(type none)
					)
				)
				(polyline
					(pts
						(xy 15.24 -10.16) (xy 16.51 -10.16)
					)
					(stroke
						(width 0)
						(type default)
					)
					(fill
						(type none)
					)
				)
				(text "LVDS"
					(at 12.7 -2.54 0)
					(effects
						(font
							(size 1.27 1.27)
						)
					)
				)
				(text "HCSL"
					(at 12.7 -10.16 0)
					(effects
						(font
							(size 1.27 1.27)
						)
					)
				)
				(pin power_in line
					(at 0 0 0)
					(length 2.54)
					(name "VDD0"
						(effects
							(font
								(size 1.27 1.27)
							)
						)
					)
					(number "13"
						(effects
							(font
								(size 1.27 1.27)
							)
						)
					)
				)
				(pin power_in line
					(at 0 -2.54 0)
					(length 2.54)
					(name "VDD1"
						(effects
							(font
								(size 1.27 1.27)
							)
						)
					)
					(number "12"
						(effects
							(font
								(size 1.27 1.27)
							)
						)
					)
				)
				(pin input line
					(at 0 -6.35 0)
					(length 2.54)
					(name "OE"
						(effects
							(font
								(size 1.27 1.27)
							)
						)
					)
					(number "1"
						(effects
							(font
								(size 1.27 1.27)
							)
						)
					)
				)
				(pin power_in line
					(at 0 -10.16 0)
					(length 2.54)
					(name "VSS"
						(effects
							(font
								(size 1.27 1.27)
							)
						)
					)
					(number "4"
						(effects
							(font
								(size 1.27 1.27)
							)
						)
					)
				)
				(pin passive line
					(at 0 -12.7 0)
					(length 2.54)
					(name "EPAD"
						(effects
							(font
								(size 1.27 1.27)
							)
						)
					)
					(number "15"
						(effects
							(font
								(size 1.27 1.27)
							)
						)
					)
				)
				(pin no_connect line
					(at 11.43 -15.24 90)
					(length 2.54)
					(hide yes)
					(name "NC"
						(effects
							(font
								(size 1.27 1.27)
							)
						)
					)
					(number "2"
						(effects
							(font
								(size 1.27 1.27)
							)
						)
					)
				)
				(pin no_connect line
					(at 12.7 -15.24 90)
					(length 2.54)
					(hide yes)
					(name "NC"
						(effects
							(font
								(size 1.27 1.27)
							)
						)
					)
					(number "3"
						(effects
							(font
								(size 1.27 1.27)
							)
						)
					)
				)
				(pin no_connect line
					(at 13.97 -15.24 90)
					(length 2.54)
					(hide yes)
					(name "NC"
						(effects
							(font
								(size 1.27 1.27)
							)
						)
					)
					(number "5"
						(effects
							(font
								(size 1.27 1.27)
							)
						)
					)
				)
				(pin no_connect line
					(at 15.24 -15.24 90)
					(length 2.54)
					(hide yes)
					(name "NC"
						(effects
							(font
								(size 1.27 1.27)
							)
						)
					)
					(number "6"
						(effects
							(font
								(size 1.27 1.27)
							)
						)
					)
				)
				(pin no_connect line
					(at 16.51 -15.24 90)
					(length 2.54)
					(hide yes)
					(name "NC"
						(effects
							(font
								(size 1.27 1.27)
							)
						)
					)
					(number "7"
						(effects
							(font
								(size 1.27 1.27)
							)
						)
					)
				)
				(pin no_connect line
					(at 17.78 -15.24 90)
					(length 2.54)
					(hide yes)
					(name "NC"
						(effects
							(font
								(size 1.27 1.27)
							)
						)
					)
					(number "14"
						(effects
							(font
								(size 1.27 1.27)
							)
						)
					)
				)
				(pin output line
					(at 26.67 -1.27 180)
					(length 2.54)
					(name "CLK0+"
						(effects
							(font
								(size 1.27 1.27)
							)
						)
					)
					(number "11"
						(effects
							(font
								(size 1.27 1.27)
							)
						)
					)
				)
				(pin output line
					(at 26.67 -3.81 180)
					(length 2.54)
					(name "CLK0-"
						(effects
							(font
								(size 1.27 1.27)
							)
						)
					)
					(number "10"
						(effects
							(font
								(size 1.27 1.27)
							)
						)
					)
				)
				(pin output line
					(at 26.67 -8.89 180)
					(length 2.54)
					(name "CLK1+"
						(effects
							(font
								(size 1.27 1.27)
							)
						)
					)
					(number "8"
						(effects
							(font
								(size 1.27 1.27)
							)
						)
					)
				)
				(pin output line
					(at 26.67 -11.43 180)
					(length 2.54)
					(name "CLK1-"
						(effects
							(font
								(size 1.27 1.27)
							)
						)
					)
					(number "9"
						(effects
							(font
								(size 1.27 1.27)
							)
						)
					)
				)
			)
		)
	(symbol "antmicroDCDCConverters:SIC477ED-T1-GE3"
			(exclude_from_sim no)
			(in_bom yes)
			(on_board yes)
			(property "Reference" "U"
				(at 50.8 -5.08 0)
				(effects
					(font
						(size 1.27 1.27)
						(thickness 0.15)
					)
					(justify left bottom)
				)
			)
			(property "Value" "SIC477ED-T1-GE3"
				(at 50.8 -7.62 0)
				(effects
					(font
						(size 1.27 1.27)
						(thickness 0.15)
					)
					(justify left bottom)
					(hide yes)
				)
			)
			(property "Footprint" "antmicro-footprints:SIC47XED-T1-GE3"
				(at 50.8 -10.16 0)
				(effects
					(font
						(size 1.27 1.27)
						(thickness 0.15)
					)
					(justify left bottom)
					(hide yes)
				)
			)
			(property "Datasheet" "https://www.vishay.com/docs/77113/sic47x.pdf"
				(at 50.8 -12.7 0)
				(effects
					(font
						(size 1.27 1.27)
						(thickness 0.15)
					)
					(justify left bottom)
					(hide yes)
				)
			)
			(property "Description" "DC/DC Synchronous Regulator, Adjustable, 4.5V to 55VIn, 0.8V to 50.6V/6AOut, 2MHz, PowerPAK MLP55-27"
				(at 0 0 0)
				(effects
					(font
						(size 1.27 1.27)
					)
					(hide yes)
				)
			)
			(property "Manufacturer" "Vishay"
				(at 50.8 -15.24 0)
				(effects
					(font
						(size 1.27 1.27)
						(thickness 0.15)
					)
					(justify left bottom)
					(hide yes)
				)
			)
			(property "MPN" "SIC477ED-T1-GE3"
				(at 50.8 -17.78 0)
				(effects
					(font
						(size 1.27 1.27)
						(thickness 0.15)
					)
					(justify left bottom)
				)
			)
			(property "Author" "Antmicro"
				(at 50.8 -20.32 0)
				(effects
					(font
						(size 1.27 1.27)
						(thickness 0.15)
					)
					(justify left bottom)
					(hide yes)
				)
			)
			(property "License" "Apache-2.0"
				(at 50.8 -22.86 0)
				(effects
					(font
						(size 1.27 1.27)
						(thickness 0.15)
					)
					(justify left bottom)
					(hide yes)
				)
			)
			(property "ki_keywords" "SMT, PMIC, IC, DC-DC, CONVERTER, SWITCHING, VOLTAGE"
				(at 0 0 0)
				(effects
					(font
						(size 1.27 1.27)
					)
					(hide yes)
				)
			)
			(symbol "SIC477ED-T1-GE3_1_1"
				(rectangle
					(start 2.54 2.54)
					(end 25.4 -27.94)
					(stroke
						(width 0.254)
						(type default)
					)
					(fill
						(type background)
					)
				)
				(pin input line
					(at 0 0 0)
					(length 2.54)
					(name "V_{CIN}"
						(effects
							(font
								(size 1.27 1.27)
							)
						)
					)
					(number "1"
						(effects
							(font
								(size 1.27 1.27)
							)
						)
					)
				)
				(pin input line
					(at 0 -2.54 0)
					(length 2.54)
					(name "V_{IN}"
						(effects
							(font
								(size 1.27 1.27)
							)
						)
					)
					(number "7"
						(effects
							(font
								(size 1.27 1.27)
							)
						)
					)
				)
				(pin passive line
					(at 0 -2.54 0)
					(length 2.54)
					(hide yes)
					(name "V_{IN}"
						(effects
							(font
								(size 1.27 1.27)
							)
						)
					)
					(number "8"
						(effects
							(font
								(size 1.27 1.27)
							)
						)
					)
				)
				(pin input line
					(at 0 -5.08 0)
					(length 2.54)
					(name "EN"
						(effects
							(font
								(size 1.27 1.27)
							)
						)
					)
					(number "3"
						(effects
							(font
								(size 1.27 1.27)
							)
						)
					)
				)
				(pin power_out line
					(at 0 -10.16 0)
					(length 2.54)
					(name "V_{DD}"
						(effects
							(font
								(size 1.27 1.27)
							)
						)
					)
					(number "26"
						(effects
							(font
								(size 1.27 1.27)
							)
						)
					)
				)
				(pin passive line
					(at 0 -12.7 0)
					(length 2.54)
					(name "V_{DRV}"
						(effects
							(font
								(size 1.27 1.27)
							)
						)
					)
					(number "16"
						(effects
							(font
								(size 1.27 1.27)
							)
						)
					)
				)
				(pin bidirectional line
					(at 0 -15.24 0)
					(length 2.54)
					(name "MODE"
						(effects
							(font
								(size 1.27 1.27)
							)
						)
					)
					(number "27"
						(effects
							(font
								(size 1.27 1.27)
							)
						)
					)
				)
				(pin passive line
					(at 0 -17.78 0)
					(length 2.54)
					(name "NC"
						(effects
							(font
								(size 1.27 1.27)
							)
						)
					)
					(number "18"
						(effects
							(font
								(size 1.27 1.27)
							)
						)
					)
				)
				(pin passive line
					(at 0 -20.32 0)
					(length 2.54)
					(name "SS"
						(effects
							(font
								(size 1.27 1.27)
							)
						)
					)
					(number "19"
						(effects
							(font
								(size 1.27 1.27)
							)
						)
					)
				)
				(pin passive line
					(at 0 -22.86 0)
					(length 2.54)
					(name "I_{LIMIT}"
						(effects
							(font
								(size 1.27 1.27)
							)
						)
					)
					(number "25"
						(effects
							(font
								(size 1.27 1.27)
							)
						)
					)
				)
				(pin passive line
					(at 0 -25.4 0)
					(length 2.54)
					(name "f_{SW}"
						(effects
							(font
								(size 1.27 1.27)
							)
						)
					)
					(number "24"
						(effects
							(font
								(size 1.27 1.27)
							)
						)
					)
				)
				(pin input line
					(at 27.94 0 180)
					(length 2.54)
					(name "BOOT"
						(effects
							(font
								(size 1.27 1.27)
							)
						)
					)
					(number "4"
						(effects
							(font
								(size 1.27 1.27)
							)
						)
					)
				)
				(pin bidirectional line
					(at 27.94 -2.54 180)
					(length 2.54)
					(name "PHASE"
						(effects
							(font
								(size 1.27 1.27)
							)
						)
					)
					(number "5"
						(effects
							(font
								(size 1.27 1.27)
							)
						)
					)
				)
				(pin passive line
					(at 27.94 -2.54 180)
					(length 2.54)
					(hide yes)
					(name "PHASE"
						(effects
							(font
								(size 1.27 1.27)
							)
						)
					)
					(number "6"
						(effects
							(font
								(size 1.27 1.27)
							)
						)
					)
				)
				(pin bidirectional line
					(at 27.94 -5.08 180)
					(length 2.54)
					(name "SW"
						(effects
							(font
								(size 1.27 1.27)
							)
						)
					)
					(number "12"
						(effects
							(font
								(size 1.27 1.27)
							)
						)
					)
				)
				(pin passive line
					(at 27.94 -5.08 180)
					(length 2.54)
					(hide yes)
					(name "SW"
						(effects
							(font
								(size 1.27 1.27)
							)
						)
					)
					(number "13"
						(effects
							(font
								(size 1.27 1.27)
							)
						)
					)
				)
				(pin passive line
					(at 27.94 -5.08 180)
					(length 2.54)
					(hide yes)
					(name "SW"
						(effects
							(font
								(size 1.27 1.27)
							)
						)
					)
					(number "14"
						(effects
							(font
								(size 1.27 1.27)
							)
						)
					)
				)
				(pin input line
					(at 27.94 -7.62 180)
					(length 2.54)
					(name "GL"
						(effects
							(font
								(size 1.27 1.27)
							)
						)
					)
					(number "15"
						(effects
							(font
								(size 1.27 1.27)
							)
						)
					)
				)
				(pin power_in line
					(at 27.94 -10.16 180)
					(length 2.54)
					(name "V_{SNS}"
						(effects
							(font
								(size 1.27 1.27)
							)
						)
					)
					(number "20"
						(effects
							(font
								(size 1.27 1.27)
							)
						)
					)
				)
				(pin input line
					(at 27.94 -12.7 180)
					(length 2.54)
					(name "V_{FB}"
						(effects
							(font
								(size 1.27 1.27)
							)
						)
					)
					(number "22"
						(effects
							(font
								(size 1.27 1.27)
							)
						)
					)
				)
				(pin passive line
					(at 27.94 -15.24 180)
					(length 2.54)
					(name "NC"
						(effects
							(font
								(size 1.27 1.27)
							)
						)
					)
					(number "21"
						(effects
							(font
								(size 1.27 1.27)
							)
						)
					)
				)
				(pin output line
					(at 27.94 -20.32 180)
					(length 2.54)
					(name "P_{GOOD}"
						(effects
							(font
								(size 1.27 1.27)
							)
						)
					)
					(number "2"
						(effects
							(font
								(size 1.27 1.27)
							)
						)
					)
				)
				(pin passive line
					(at 27.94 -22.86 180)
					(length 2.54)
					(hide yes)
					(name "PGND"
						(effects
							(font
								(size 1.27 1.27)
							)
						)
					)
					(number "10"
						(effects
							(font
								(size 1.27 1.27)
							)
						)
					)
				)
				(pin passive line
					(at 27.94 -22.86 180)
					(length 2.54)
					(hide yes)
					(name "PGND"
						(effects
							(font
								(size 1.27 1.27)
							)
						)
					)
					(number "11"
						(effects
							(font
								(size 1.27 1.27)
							)
						)
					)
				)
				(pin passive line
					(at 27.94 -22.86 180)
					(length 2.54)
					(hide yes)
					(name "PGND"
						(effects
							(font
								(size 1.27 1.27)
							)
						)
					)
					(number "17"
						(effects
							(font
								(size 1.27 1.27)
							)
						)
					)
				)
				(pin power_in line
					(at 27.94 -22.86 180)
					(length 2.54)
					(name "PGND"
						(effects
							(font
								(size 1.27 1.27)
							)
						)
					)
					(number "9"
						(effects
							(font
								(size 1.27 1.27)
							)
						)
					)
				)
				(pin power_in line
					(at 27.94 -25.4 180)
					(length 2.54)
					(name "AGND"
						(effects
							(font
								(size 1.27 1.27)
							)
						)
					)
					(number "23"
						(effects
							(font
								(size 1.27 1.27)
							)
						)
					)
				)
				(pin passive line
					(at 27.94 -25.4 180)
					(length 2.54)
					(hide yes)
					(name "AGND"
						(effects
							(font
								(size 1.27 1.27)
							)
						)
					)
					(number "28"
						(effects
							(font
								(size 1.27 1.27)
							)
						)
					)
				)
			)
		)
	(symbol "antmicroDCDCConverters:TPS56C230"
			(exclude_from_sim no)
			(in_bom yes)
			(on_board yes)
			(property "Reference" "U"
				(at 33.02 -2.54 0)
				(effects
					(font
						(size 1.27 1.27)
						(thickness 0.15)
					)
					(justify left bottom)
				)
			)
			(property "Value" "TPS56C230"
				(at 33.02 -5.08 0)
				(effects
					(font
						(size 1.27 1.27)
						(thickness 0.15)
					)
					(justify left bottom)
					(hide yes)
				)
			)
			(property "Footprint" "antmicro-footprints:QFN-20-1EP_3x3mm_P0.45mm"
				(at 33.02 -7.62 0)
				(effects
					(font
						(size 1.27 1.27)
						(thickness 0.15)
					)
					(justify left bottom)
					(hide yes)
				)
			)
			(property "Datasheet" "https://www.ti.com/lit/ds/symlink/tps56c230.pdf"
				(at 33.02 -10.16 0)
				(effects
					(font
						(size 1.27 1.27)
						(thickness 0.15)
					)
					(justify left bottom)
					(hide yes)
				)
			)
			(property "Description" "DC/DC converter"
				(at 0 0 0)
				(effects
					(font
						(size 1.27 1.27)
					)
					(hide yes)
				)
			)
			(property "Manufacturer" "Texas Instruments"
				(at 33.02 -12.7 0)
				(effects
					(font
						(size 1.27 1.27)
						(thickness 0.15)
					)
					(justify left bottom)
					(hide yes)
				)
			)
			(property "MPN" "TPS56C230RJER"
				(at 33.02 -15.24 0)
				(effects
					(font
						(size 1.27 1.27)
						(thickness 0.15)
					)
					(justify left bottom)
				)
			)
			(property "Author" "Antmicro"
				(at 33.02 -17.78 0)
				(effects
					(font
						(size 1.27 1.27)
						(thickness 0.15)
					)
					(justify left bottom)
					(hide yes)
				)
			)
			(property "License" "Apache-2.0"
				(at 33.02 -20.32 0)
				(effects
					(font
						(size 1.27 1.27)
						(thickness 0.15)
					)
					(justify left bottom)
					(hide yes)
				)
			)
			(property "ki_keywords" "SMT, PMIC, IC, SWITCHING, VOLTAGE, REGULATOR, DC-DC"
				(at 0 0 0)
				(effects
					(font
						(size 1.27 1.27)
					)
					(hide yes)
				)
			)
			(symbol "TPS56C230_1_1"
				(rectangle
					(start 2.54 2.54)
					(end 15.24 -25.4)
					(stroke
						(width 0.254)
						(type default)
					)
					(fill
						(type background)
					)
				)
				(pin power_in line
					(at 0 0 0)
					(length 2.54)
					(name "V_{IN}"
						(effects
							(font
								(size 1.27 1.27)
							)
						)
					)
					(number "2"
						(effects
							(font
								(size 1.27 1.27)
							)
						)
					)
				)
				(pin passive line
					(at 0 0 0)
					(length 2.54)
					(hide yes)
					(name "V_{IN}"
						(effects
							(font
								(size 1.27 1.27)
							)
						)
					)
					(number "3"
						(effects
							(font
								(size 1.27 1.27)
							)
						)
					)
				)
				(pin passive line
					(at 0 0 0)
					(length 2.54)
					(hide yes)
					(name "V_{IN}"
						(effects
							(font
								(size 1.27 1.27)
							)
						)
					)
					(number "4"
						(effects
							(font
								(size 1.27 1.27)
							)
						)
					)
				)
				(pin passive line
					(at 0 0 0)
					(length 2.54)
					(hide yes)
					(name "V_{IN}"
						(effects
							(font
								(size 1.27 1.27)
							)
						)
					)
					(number "5"
						(effects
							(font
								(size 1.27 1.27)
							)
						)
					)
				)
				(pin passive line
					(at 0 -5.08 0)
					(length 2.54)
					(name "EN"
						(effects
							(font
								(size 1.27 1.27)
							)
						)
					)
					(number "12"
						(effects
							(font
								(size 1.27 1.27)
							)
						)
					)
				)
				(pin passive line
					(at 0 -10.16 0)
					(length 2.54)
					(name "V_{CC}"
						(effects
							(font
								(size 1.27 1.27)
							)
						)
					)
					(number "17"
						(effects
							(font
								(size 1.27 1.27)
							)
						)
					)
				)
				(pin passive line
					(at 0 -17.78 0)
					(length 2.54)
					(name "PG"
						(effects
							(font
								(size 1.27 1.27)
							)
						)
					)
					(number "9"
						(effects
							(font
								(size 1.27 1.27)
							)
						)
					)
				)
				(pin passive line
					(at 0 -22.86 0)
					(length 2.54)
					(name "MODE"
						(effects
							(font
								(size 1.27 1.27)
							)
						)
					)
					(number "15"
						(effects
							(font
								(size 1.27 1.27)
							)
						)
					)
				)
				(pin no_connect line
					(at 15.24 -12.7 180)
					(length 2.54)
					(hide yes)
					(name "NC"
						(effects
							(font
								(size 1.27 1.27)
							)
						)
					)
					(number "16"
						(effects
							(font
								(size 1.27 1.27)
							)
						)
					)
				)
				(pin no_connect line
					(at 15.24 -17.78 180)
					(length 2.54)
					(hide yes)
					(name "NC"
						(effects
							(font
								(size 1.27 1.27)
							)
						)
					)
					(number "10"
						(effects
							(font
								(size 1.27 1.27)
							)
						)
					)
				)
				(pin passive line
					(at 17.78 0 180)
					(length 2.54)
					(name "BST"
						(effects
							(font
								(size 1.27 1.27)
							)
						)
					)
					(number "1"
						(effects
							(font
								(size 1.27 1.27)
							)
						)
					)
				)
				(pin passive line
					(at 17.78 -5.08 180)
					(length 2.54)
					(name "SW"
						(effects
							(font
								(size 1.27 1.27)
							)
						)
					)
					(number "19"
						(effects
							(font
								(size 1.27 1.27)
							)
						)
					)
				)
				(pin passive line
					(at 17.78 -5.08 180)
					(length 2.54)
					(hide yes)
					(name "SW"
						(effects
							(font
								(size 1.27 1.27)
							)
						)
					)
					(number "20"
						(effects
							(font
								(size 1.27 1.27)
							)
						)
					)
				)
				(pin passive line
					(at 17.78 -5.08 180)
					(length 2.54)
					(hide yes)
					(name "SW"
						(effects
							(font
								(size 1.27 1.27)
							)
						)
					)
					(number "6"
						(effects
							(font
								(size 1.27 1.27)
							)
						)
					)
				)
				(pin passive line
					(at 17.78 -10.16 180)
					(length 2.54)
					(name "FB"
						(effects
							(font
								(size 1.27 1.27)
							)
						)
					)
					(number "14"
						(effects
							(font
								(size 1.27 1.27)
							)
						)
					)
				)
				(pin passive line
					(at 17.78 -15.24 180)
					(length 2.54)
					(name "SS"
						(effects
							(font
								(size 1.27 1.27)
							)
						)
					)
					(number "11"
						(effects
							(font
								(size 1.27 1.27)
							)
						)
					)
				)
				(pin passive line
					(at 17.78 -20.32 180)
					(length 2.54)
					(name "AGND"
						(effects
							(font
								(size 1.27 1.27)
							)
						)
					)
					(number "13"
						(effects
							(font
								(size 1.27 1.27)
							)
						)
					)
				)
				(pin passive line
					(at 17.78 -22.86 180)
					(length 2.54)
					(name "PGND"
						(effects
							(font
								(size 1.27 1.27)
							)
						)
					)
					(number "18"
						(effects
							(font
								(size 1.27 1.27)
							)
						)
					)
				)
				(pin passive line
					(at 17.78 -22.86 180)
					(length 2.54)
					(hide yes)
					(name "PGND"
						(effects
							(font
								(size 1.27 1.27)
							)
						)
					)
					(number "21"
						(effects
							(font
								(size 1.27 1.27)
							)
						)
					)
				)
				(pin passive line
					(at 17.78 -22.86 180)
					(length 2.54)
					(hide yes)
					(name "PGND"
						(effects
							(font
								(size 1.27 1.27)
							)
						)
					)
					(number "7"
						(effects
							(font
								(size 1.27 1.27)
							)
						)
					)
				)
				(pin passive line
					(at 17.78 -22.86 180)
					(length 2.54)
					(hide yes)
					(name "PGND"
						(effects
							(font
								(size 1.27 1.27)
							)
						)
					)
					(number "8"
						(effects
							(font
								(size 1.27 1.27)
							)
						)
					)
				)
			)
		)
	(symbol "antmicroFixedInductors:L_1u8_6.8A_WE-MAPI-4020"
			(pin_numbers
				(hide yes)
			)
			(pin_names
				(hide yes)
			)
			(exclude_from_sim no)
			(in_bom yes)
			(on_board yes)
			(property "Reference" "L"
				(at 13.97 0 0)
				(effects
					(font
						(size 1.27 1.27)
						(thickness 0.15)
					)
					(justify left bottom)
				)
			)
			(property "Value" "L_1u8_6.8A_WE-MAPI-4020"
				(at 13.97 -2.54 0)
				(effects
					(font
						(size 1.27 1.27)
						(thickness 0.15)
					)
					(justify left bottom)
					(hide yes)
				)
			)
			(property "Footprint" "antmicro-footprints:L_WE-MAPI-4020"
				(at 13.97 -7.62 0)
				(effects
					(font
						(size 1.27 1.27)
						(thickness 0.15)
					)
					(justify left bottom)
					(hide yes)
				)
			)
			(property "Datasheet" "https://www.we-online.com/components/products/datasheet/74438356018.pdf"
				(at 13.97 -10.16 0)
				(effects
					(font
						(size 1.27 1.27)
						(thickness 0.15)
					)
					(justify left bottom)
					(hide yes)
				)
			)
			(property "Description" "Power Inductors - SMD WE-MAPI 1.8uH 4.6A DCR=30mOhms AEC-Q200"
				(at 0 0 0)
				(effects
					(font
						(size 1.27 1.27)
					)
					(hide yes)
				)
			)
			(property "Val" "1u8/6.8A"
				(at 13.97 -5.08 0)
				(effects
					(font
						(size 1.27 1.27)
						(thickness 0.15)
					)
					(justify left bottom)
				)
			)
			(property "Manufacturer" "Würth Elektronik"
				(at 13.97 -12.7 0)
				(effects
					(font
						(size 1.27 1.27)
						(thickness 0.15)
					)
					(justify left bottom)
					(hide yes)
				)
			)
			(property "MPN" "74438356018"
				(at 13.97 -15.24 0)
				(effects
					(font
						(size 1.27 1.27)
						(thickness 0.15)
					)
					(justify left bottom)
					(hide yes)
				)
			)
			(property "ISat" "6.5 A"
				(at 13.97 -16.51 0)
				(effects
					(font
						(size 1.27 1.27)
					)
					(justify left)
					(hide yes)
				)
			)
			(property "IMax" "6.8 A"
				(at 13.97 -20.32 0)
				(effects
					(font
						(size 1.27 1.27)
						(thickness 0.15)
					)
					(justify left bottom)
					(hide yes)
				)
			)
			(property "Size" "4.1x4.1mm"
				(at 13.97 -22.86 0)
				(effects
					(font
						(size 1.27 1.27)
						(thickness 0.15)
					)
					(justify left bottom)
					(hide yes)
				)
			)
			(property "Author" "Antmicro"
				(at 13.97 -25.4 0)
				(effects
					(font
						(size 1.27 1.27)
						(thickness 0.15)
					)
					(justify left bottom)
					(hide yes)
				)
			)
			(property "License" "Apache-2.0"
				(at 13.97 -27.94 0)
				(effects
					(font
						(size 1.27 1.27)
						(thickness 0.15)
					)
					(justify left bottom)
					(hide yes)
				)
			)
			(property "ki_keywords" "SMT, INDUCTOR, PASSIVE"
				(at 0 0 0)
				(effects
					(font
						(size 1.27 1.27)
					)
					(hide yes)
				)
			)
			(symbol "L_1u8_6.8A_WE-MAPI-4020_0_1"
				(arc
					(start 0.508 0)
					(mid 1.016 0.5058)
					(end 1.524 0)
					(stroke
						(width 0)
						(type default)
					)
					(fill
						(type none)
					)
				)
				(arc
					(start 1.524 0)
					(mid 2.032 0.5058)
					(end 2.54 0)
					(stroke
						(width 0)
						(type default)
					)
					(fill
						(type none)
					)
				)
				(arc
					(start 2.54 0)
					(mid 3.048 0.5058)
					(end 3.556 0)
					(stroke
						(width 0)
						(type default)
					)
					(fill
						(type none)
					)
				)
				(arc
					(start 3.556 0)
					(mid 4.064 0.5058)
					(end 4.572 0)
					(stroke
						(width 0)
						(type default)
					)
					(fill
						(type none)
					)
				)
			)
			(symbol "L_1u8_6.8A_WE-MAPI-4020_1_1"
				(pin passive line
					(at 0 0 0)
					(length 0.508)
					(name "~"
						(effects
							(font
								(size 1.27 1.27)
							)
						)
					)
					(number "1"
						(effects
							(font
								(size 1.27 1.27)
							)
						)
					)
				)
				(pin passive line
					(at 5.08 0 180)
					(length 0.508)
					(name "~"
						(effects
							(font
								(size 1.27 1.27)
							)
						)
					)
					(number "2"
						(effects
							(font
								(size 1.27 1.27)
							)
						)
					)
				)
			)
		)
	(symbol "antmicroFixedInductors:L_4u7_14.6A_Abracon-Q8080"
			(pin_numbers
				(hide yes)
			)
			(pin_names
				(hide yes)
			)
			(exclude_from_sim no)
			(in_bom yes)
			(on_board yes)
			(property "Reference" "L"
				(at 15.24 -5.08 0)
				(effects
					(font
						(size 1.27 1.27)
						(thickness 0.15)
					)
					(justify left bottom)
				)
			)
			(property "Value" "L_4u7_14.6A_Abracon-Q8080"
				(at 15.24 -10.16 0)
				(effects
					(font
						(size 1.27 1.27)
						(thickness 0.15)
					)
					(justify left bottom)
					(hide yes)
				)
			)
			(property "Footprint" "antmicro-footprints:L_Abracon_ASPIAIG-Q8080"
				(at 15.24 -12.7 0)
				(effects
					(font
						(size 1.27 1.27)
						(thickness 0.15)
					)
					(justify left bottom)
					(hide yes)
				)
			)
			(property "Datasheet" "https://www.mouser.com/datasheet/2/3/ASPIAIG_Q8080-2256550.pdf"
				(at 15.24 -15.24 0)
				(effects
					(font
						(size 1.27 1.27)
						(thickness 0.15)
					)
					(justify left bottom)
					(hide yes)
				)
			)
			(property "Description" "Power Inductors - SMD 4.7 UH 20%"
				(at 0 0 0)
				(effects
					(font
						(size 1.27 1.27)
					)
					(hide yes)
				)
			)
			(property "MPN" "ASPIAIG-Q8080-4R7M-T"
				(at 15.24 -17.78 0)
				(effects
					(font
						(size 1.27 1.27)
						(thickness 0.15)
					)
					(justify left bottom)
					(hide yes)
				)
			)
			(property "ISat" "17A"
				(at 15.24 -20.32 0)
				(effects
					(font
						(size 1.27 1.27)
						(thickness 0.15)
					)
					(justify left bottom)
					(hide yes)
				)
			)
			(property "IMax" "14.6A"
				(at 15.24 -22.86 0)
				(effects
					(font
						(size 1.27 1.27)
						(thickness 0.15)
					)
					(justify left bottom)
					(hide yes)
				)
			)
			(property "Size" "8.9x8.5"
				(at 15.24 -25.4 0)
				(effects
					(font
						(size 1.27 1.27)
						(thickness 0.15)
					)
					(justify left bottom)
					(hide yes)
				)
			)
			(property "Val" "4.7u/14.6A"
				(at 15.24 -7.62 0)
				(effects
					(font
						(size 1.27 1.27)
						(thickness 0.15)
					)
					(justify left bottom)
				)
			)
			(property "Author" "Antmicro"
				(at 15.24 -27.94 0)
				(effects
					(font
						(size 1.27 1.27)
						(thickness 0.15)
					)
					(justify left bottom)
					(hide yes)
				)
			)
			(property "License" "Apache-2.0"
				(at 15.24 -30.48 0)
				(effects
					(font
						(size 1.27 1.27)
						(thickness 0.15)
					)
					(justify left bottom)
					(hide yes)
				)
			)
			(property "Manufacturer" "Abracon"
				(at 15.24 -33.02 0)
				(effects
					(font
						(size 1.27 1.27)
						(thickness 0.15)
					)
					(justify left bottom)
					(hide yes)
				)
			)
			(property "ki_keywords" "SMT, INDUCTOR, PASSIVE"
				(at 0 0 0)
				(effects
					(font
						(size 1.27 1.27)
					)
					(hide yes)
				)
			)
			(symbol "L_4u7_14.6A_Abracon-Q8080_0_1"
				(arc
					(start 0.508 0)
					(mid 1.016 0.5058)
					(end 1.524 0)
					(stroke
						(width 0)
						(type default)
					)
					(fill
						(type none)
					)
				)
				(arc
					(start 1.524 0)
					(mid 2.032 0.5058)
					(end 2.54 0)
					(stroke
						(width 0)
						(type default)
					)
					(fill
						(type none)
					)
				)
				(arc
					(start 2.54 0)
					(mid 3.048 0.5058)
					(end 3.556 0)
					(stroke
						(width 0)
						(type default)
					)
					(fill
						(type none)
					)
				)
				(arc
					(start 3.556 0)
					(mid 4.064 0.5058)
					(end 4.572 0)
					(stroke
						(width 0)
						(type default)
					)
					(fill
						(type none)
					)
				)
			)
			(symbol "L_4u7_14.6A_Abracon-Q8080_1_1"
				(pin passive line
					(at 0 0 0)
					(length 0.508)
					(name "~"
						(effects
							(font
								(size 1.27 1.27)
							)
						)
					)
					(number "1"
						(effects
							(font
								(size 1.27 1.27)
							)
						)
					)
				)
				(pin passive line
					(at 5.08 0 180)
					(length 0.508)
					(name "~"
						(effects
							(font
								(size 1.27 1.27)
							)
						)
					)
					(number "2"
						(effects
							(font
								(size 1.27 1.27)
							)
						)
					)
				)
			)
		)
	(symbol "antmicroFuses:F_7A_1206"
			(pin_numbers
				(hide yes)
			)
			(pin_names
				(hide yes)
			)
			(exclude_from_sim no)
			(in_bom yes)
			(on_board yes)
			(property "Reference" "F"
				(at 21.59 -5.08 0)
				(effects
					(font
						(size 1.27 1.27)
						(thickness 0.15)
					)
					(justify left bottom)
				)
			)
			(property "Value" "F_7A_1206"
				(at 21.59 -7.62 0)
				(effects
					(font
						(size 1.27 1.27)
						(thickness 0.15)
					)
					(justify left bottom)
					(hide yes)
				)
			)
			(property "Footprint" "antmicro-footprints:F_1206_3216Metric"
				(at 21.59 -10.16 0)
				(effects
					(font
						(size 1.27 1.27)
						(thickness 0.15)
					)
					(justify left bottom)
					(hide yes)
				)
			)
			(property "Datasheet" "https://us.schurter.com/pdf/english/typ_UST_1206.pdf"
				(at 21.59 -12.7 0)
				(effects
					(font
						(size 1.27 1.27)
						(thickness 0.15)
					)
					(justify left bottom)
					(hide yes)
				)
			)
			(property "Description" "7 A 32 V AC 63 V DC Fuse Board Mount (Cartridge Style Excluded) Surface Mount 1206 (3216 Metric)"
				(at 0 0 0)
				(effects
					(font
						(size 1.27 1.27)
					)
					(hide yes)
				)
			)
			(property "Manufacturer" "Schurter"
				(at 21.59 -15.24 0)
				(effects
					(font
						(size 1.27 1.27)
						(thickness 0.15)
					)
					(justify left bottom)
					(hide yes)
				)
			)
			(property "MPN" "3413.0326.11"
				(at 21.59 -17.78 0)
				(effects
					(font
						(size 1.27 1.27)
						(thickness 0.15)
					)
					(justify left bottom)
				)
			)
			(property "Author" "Antmicro"
				(at 21.59 -20.32 0)
				(effects
					(font
						(size 1.27 1.27)
						(thickness 0.15)
					)
					(justify left bottom)
					(hide yes)
				)
			)
			(property "License" "Apache-2.0"
				(at 21.59 -22.86 0)
				(effects
					(font
						(size 1.27 1.27)
						(thickness 0.15)
					)
					(justify left bottom)
					(hide yes)
				)
			)
			(property "ki_keywords" "FUSE, PASSIVE"
				(at 0 0 0)
				(effects
					(font
						(size 1.27 1.27)
					)
					(hide yes)
				)
			)
			(symbol "F_7A_1206_0_1"
				(rectangle
					(start 1.27 0.508)
					(end 3.81 -0.508)
					(stroke
						(width 0)
						(type default)
					)
					(fill
						(type none)
					)
				)
				(polyline
					(pts
						(xy 1.27 0) (xy 3.81 0)
					)
					(stroke
						(width 0)
						(type default)
					)
					(fill
						(type none)
					)
				)
			)
			(symbol "F_7A_1206_1_1"
				(pin passive line
					(at 0 0 0)
					(length 1.27)
					(name "~"
						(effects
							(font
								(size 1.27 1.27)
							)
						)
					)
					(number "1"
						(effects
							(font
								(size 1.27 1.27)
							)
						)
					)
				)
				(pin passive line
					(at 5.08 0 180)
					(length 1.27)
					(name "~"
						(effects
							(font
								(size 1.27 1.27)
							)
						)
					)
					(number "2"
						(effects
							(font
								(size 1.27 1.27)
							)
						)
					)
				)
			)
		)
	(symbol "antmicroInterfaceControllers:CYPD3177-24LQXQ"
			(exclude_from_sim no)
			(in_bom yes)
			(on_board yes)
			(property "Reference" "U"
				(at 48.26 -2.54 0)
				(effects
					(font
						(size 1.27 1.27)
						(thickness 0.15)
					)
					(justify left bottom)
				)
			)
			(property "Value" "CYPD3177-24LQXQ"
				(at 48.26 -7.62 0)
				(effects
					(font
						(size 1.27 1.27)
						(thickness 0.15)
					)
					(justify left bottom)
					(hide yes)
				)
			)
			(property "Footprint" "antmicro-footprints:QFN-24-1EP_4x4mm_P0.5mm_EP2.6x2.6mm"
				(at 48.26 -10.16 0)
				(effects
					(font
						(size 1.27 1.27)
						(thickness 0.15)
					)
					(justify left bottom)
					(hide yes)
				)
			)
			(property "Datasheet" "https://www.infineon.com/dgdl/Infineon-EZ-PD_BCR_Datasheet_USB_Type-C_Port_Controller_for_Power_Sinks-DataSheet-v03_00-EN.pdf?fileId=8ac78c8c7d0d8da4017d0ee7ce9d70ad"
				(at 48.26 -12.7 0)
				(effects
					(font
						(size 1.27 1.27)
						(thickness 0.15)
					)
					(justify left bottom)
					(hide yes)
				)
			)
			(property "Description" "USB Interface, USB Type-C and Power Delivery (PD) Controller, USB PD 3.0, 2.7 V, 5.5 V, QFN-EP"
				(at 0 0 0)
				(effects
					(font
						(size 1.27 1.27)
					)
					(hide yes)
				)
			)
			(property "MPN" "CYPD3177-24LQXQ"
				(at 48.26 -5.08 0)
				(effects
					(font
						(size 1.27 1.27)
						(thickness 0.15)
					)
					(justify left bottom)
				)
			)
			(property "Manufacturer" "Infineon"
				(at 48.26 -15.24 0)
				(effects
					(font
						(size 1.27 1.27)
						(thickness 0.15)
					)
					(justify left bottom)
					(hide yes)
				)
			)
			(property "Author" "Antmicro"
				(at 48.26 -17.78 0)
				(effects
					(font
						(size 1.27 1.27)
						(thickness 0.15)
					)
					(justify left bottom)
					(hide yes)
				)
			)
			(property "License" "Apache-2.0"
				(at 48.26 -20.32 0)
				(effects
					(font
						(size 1.27 1.27)
						(thickness 0.15)
					)
					(justify left bottom)
					(hide yes)
				)
			)
			(property "ki_keywords" "SMT, CONTROLLER, IC, INTERFACE"
				(at 0 0 0)
				(effects
					(font
						(size 1.27 1.27)
					)
					(hide yes)
				)
			)
			(symbol "CYPD3177-24LQXQ_1_1"
				(rectangle
					(start 2.54 2.54)
					(end 30.48 -43.18)
					(stroke
						(width 0.254)
						(type default)
					)
					(fill
						(type background)
					)
				)
				(pin power_in line
					(at 0 0 0)
					(length 2.54)
					(name "VBUS_IN"
						(effects
							(font
								(size 1.27 1.27)
							)
						)
					)
					(number "18"
						(effects
							(font
								(size 1.27 1.27)
							)
						)
					)
				)
				(pin passive line
					(at 0 -5.08 0)
					(length 2.54)
					(name "CC2"
						(effects
							(font
								(size 1.27 1.27)
							)
						)
					)
					(number "14"
						(effects
							(font
								(size 1.27 1.27)
							)
						)
					)
				)
				(pin passive line
					(at 0 -7.62 0)
					(length 2.54)
					(name "CC1"
						(effects
							(font
								(size 1.27 1.27)
							)
						)
					)
					(number "15"
						(effects
							(font
								(size 1.27 1.27)
							)
						)
					)
				)
				(pin passive line
					(at 0 -12.7 0)
					(length 2.54)
					(name "D+"
						(effects
							(font
								(size 1.27 1.27)
							)
						)
					)
					(number "17"
						(effects
							(font
								(size 1.27 1.27)
							)
						)
					)
				)
				(pin passive line
					(at 0 -15.24 0)
					(length 2.54)
					(name "D-"
						(effects
							(font
								(size 1.27 1.27)
							)
						)
					)
					(number "16"
						(effects
							(font
								(size 1.27 1.27)
							)
						)
					)
				)
				(pin input line
					(at 0 -20.32 0)
					(length 2.54)
					(name "VBUS_MIN"
						(effects
							(font
								(size 1.27 1.27)
							)
						)
					)
					(number "1"
						(effects
							(font
								(size 1.27 1.27)
							)
						)
					)
				)
				(pin input line
					(at 0 -22.86 0)
					(length 2.54)
					(name "VBUS_MAX"
						(effects
							(font
								(size 1.27 1.27)
							)
						)
					)
					(number "2"
						(effects
							(font
								(size 1.27 1.27)
							)
						)
					)
				)
				(pin input line
					(at 0 -25.4 0)
					(length 2.54)
					(name "ISNK_COARSE"
						(effects
							(font
								(size 1.27 1.27)
							)
						)
					)
					(number "5"
						(effects
							(font
								(size 1.27 1.27)
							)
						)
					)
				)
				(pin input line
					(at 0 -27.94 0)
					(length 2.54)
					(name "ISNK_FINE"
						(effects
							(font
								(size 1.27 1.27)
							)
						)
					)
					(number "6"
						(effects
							(font
								(size 1.27 1.27)
							)
						)
					)
				)
				(pin passive line
					(at 0 -33.02 0)
					(length 2.54)
					(name "VDDD"
						(effects
							(font
								(size 1.27 1.27)
							)
						)
					)
					(number "23"
						(effects
							(font
								(size 1.27 1.27)
							)
						)
					)
				)
				(pin passive line
					(at 0 -35.56 0)
					(length 2.54)
					(name "VCCD"
						(effects
							(font
								(size 1.27 1.27)
							)
						)
					)
					(number "24"
						(effects
							(font
								(size 1.27 1.27)
							)
						)
					)
				)
				(pin power_in line
					(at 0 -40.64 0)
					(length 2.54)
					(name "GND"
						(effects
							(font
								(size 1.27 1.27)
							)
						)
					)
					(number "19"
						(effects
							(font
								(size 1.27 1.27)
							)
						)
					)
				)
				(pin passive line
					(at 0 -40.64 0)
					(length 2.54)
					(hide yes)
					(name "GND"
						(effects
							(font
								(size 1.27 1.27)
							)
						)
					)
					(number "22"
						(effects
							(font
								(size 1.27 1.27)
							)
						)
					)
				)
				(pin passive line
					(at 0 -40.64 0)
					(length 2.54)
					(hide yes)
					(name "GND"
						(effects
							(font
								(size 1.27 1.27)
							)
						)
					)
					(number "25"
						(effects
							(font
								(size 1.27 1.27)
							)
						)
					)
				)
				(pin output line
					(at 33.02 0 180)
					(length 2.54)
					(name "VBUS_FET_EN"
						(effects
							(font
								(size 1.27 1.27)
							)
						)
					)
					(number "3"
						(effects
							(font
								(size 1.27 1.27)
							)
						)
					)
				)
				(pin output line
					(at 33.02 -2.54 180)
					(length 2.54)
					(name "SAFE_PWR_EN"
						(effects
							(font
								(size 1.27 1.27)
							)
						)
					)
					(number "4"
						(effects
							(font
								(size 1.27 1.27)
							)
						)
					)
				)
				(pin passive line
					(at 33.02 -7.62 180)
					(length 2.54)
					(name "VDC_OUT"
						(effects
							(font
								(size 1.27 1.27)
							)
						)
					)
					(number "11"
						(effects
							(font
								(size 1.27 1.27)
							)
						)
					)
				)
				(pin passive line
					(at 33.02 -12.7 180)
					(length 2.54)
					(name "HPI_SCL"
						(effects
							(font
								(size 1.27 1.27)
							)
						)
					)
					(number "13"
						(effects
							(font
								(size 1.27 1.27)
							)
						)
					)
				)
				(pin passive line
					(at 33.02 -15.24 180)
					(length 2.54)
					(name "HPI_SDA"
						(effects
							(font
								(size 1.27 1.27)
							)
						)
					)
					(number "12"
						(effects
							(font
								(size 1.27 1.27)
							)
						)
					)
				)
				(pin passive line
					(at 33.02 -17.78 180)
					(length 2.54)
					(name "~{HPI_INT}"
						(effects
							(font
								(size 1.27 1.27)
							)
						)
					)
					(number "7"
						(effects
							(font
								(size 1.27 1.27)
							)
						)
					)
				)
				(pin passive line
					(at 33.02 -22.86 180)
					(length 2.54)
					(name "GPIO_1"
						(effects
							(font
								(size 1.27 1.27)
							)
						)
					)
					(number "8"
						(effects
							(font
								(size 1.27 1.27)
							)
						)
					)
				)
				(pin output line
					(at 33.02 -27.94 180)
					(length 2.54)
					(name "FAULT"
						(effects
							(font
								(size 1.27 1.27)
							)
						)
					)
					(number "9"
						(effects
							(font
								(size 1.27 1.27)
							)
						)
					)
				)
				(pin open_collector line
					(at 33.02 -30.48 180)
					(length 2.54)
					(name "FLIP"
						(effects
							(font
								(size 1.27 1.27)
							)
						)
					)
					(number "10"
						(effects
							(font
								(size 1.27 1.27)
							)
						)
					)
				)
				(pin no_connect line
					(at 33.02 -38.1 180)
					(length 2.54)
					(name "DNU2"
						(effects
							(font
								(size 1.27 1.27)
							)
						)
					)
					(number "21"
						(effects
							(font
								(size 1.27 1.27)
							)
						)
					)
				)
				(pin no_connect line
					(at 33.02 -40.64 180)
					(length 2.54)
					(name "DNU1"
						(effects
							(font
								(size 1.27 1.27)
							)
						)
					)
					(number "20"
						(effects
							(font
								(size 1.27 1.27)
							)
						)
					)
				)
			)
		)
	(symbol "antmicroLEDIndicationDiscrete:LED_G_0603_LTST-C190GKT"
			(pin_numbers
				(hide yes)
			)
			(pin_names
				(hide yes)
			)
			(exclude_from_sim no)
			(in_bom yes)
			(on_board yes)
			(property "Reference" "D"
				(at 22.86 -2.54 0)
				(effects
					(font
						(size 1.27 1.27)
						(thickness 0.15)
					)
					(justify left bottom)
				)
			)
			(property "Value" "LED_G_0603_LTST-C190GKT"
				(at 22.86 -7.62 0)
				(effects
					(font
						(size 1.27 1.27)
						(thickness 0.15)
					)
					(justify left bottom)
					(hide yes)
				)
			)
			(property "Footprint" "antmicro-footprints:LED_0603_1608Metric_G"
				(at 22.86 -10.16 0)
				(effects
					(font
						(size 1.27 1.27)
						(thickness 0.15)
					)
					(justify left bottom)
					(hide yes)
				)
			)
			(property "Datasheet" "https://media.digikey.com/pdf/Data%20Sheets/Lite-On%20PDFs/LTST-C190GKT.pdf"
				(at 22.86 -12.7 0)
				(effects
					(font
						(size 1.27 1.27)
						(thickness 0.15)
					)
					(justify left bottom)
					(hide yes)
				)
			)
			(property "Description" "LED, Green, SMD, 0603, 20 mA, 2.1 V, 569 nm"
				(at 0 0 0)
				(effects
					(font
						(size 1.27 1.27)
					)
					(hide yes)
				)
			)
			(property "MPN" "LTST-C190GKT"
				(at 22.86 -15.24 0)
				(effects
					(font
						(size 1.27 1.27)
						(thickness 0.15)
					)
					(justify left bottom)
					(hide yes)
				)
			)
			(property "Manufacturer" "Lite-On"
				(at 22.86 -17.78 0)
				(effects
					(font
						(size 1.27 1.27)
						(thickness 0.15)
					)
					(justify left bottom)
					(hide yes)
				)
			)
			(property "Color" "Green"
				(at 22.86 -5.08 0)
				(effects
					(font
						(size 1.27 1.27)
					)
					(justify left bottom)
				)
			)
			(property "Author" "Antmicro"
				(at 22.86 -20.32 0)
				(effects
					(font
						(size 1.27 1.27)
						(thickness 0.15)
					)
					(justify left bottom)
					(hide yes)
				)
			)
			(property "License" "Apache-2.0"
				(at 22.86 -22.86 0)
				(effects
					(font
						(size 1.27 1.27)
						(thickness 0.15)
					)
					(justify left bottom)
					(hide yes)
				)
			)
			(property "ki_keywords" "SMT, DIODE, SEMICONDUCTOR, LED"
				(at 0 0 0)
				(effects
					(font
						(size 1.27 1.27)
					)
					(hide yes)
				)
			)
			(symbol "LED_G_0603_LTST-C190GKT_0_1"
				(polyline
					(pts
						(xy 1.905 0) (xy 0.635 0)
					)
					(stroke
						(width 0)
						(type default)
					)
					(fill
						(type none)
					)
				)
				(polyline
					(pts
						(xy 4.445 0) (xy 3.175 0)
					)
					(stroke
						(width 0)
						(type default)
					)
					(fill
						(type none)
					)
				)
			)
			(symbol "LED_G_0603_LTST-C190GKT_1_1"
				(polyline
					(pts
						(xy 1.143 2.286) (xy 1.143 1.778) (xy 1.143 2.286) (xy 1.651 2.286) (xy 1.143 2.286) (xy 2.159 1.27)
					)
					(stroke
						(width 0.254)
						(type default)
					)
					(fill
						(type none)
					)
				)
				(polyline
					(pts
						(xy 1.778 1.016) (xy 1.778 -1.016)
					)
					(stroke
						(width 0.254)
						(type default)
					)
					(fill
						(type none)
					)
				)
				(polyline
					(pts
						(xy 2.159 2.54) (xy 2.159 2.032) (xy 2.159 2.54) (xy 2.667 2.54) (xy 2.159 2.54) (xy 3.048 1.651)
					)
					(stroke
						(width 0.254)
						(type default)
					)
					(fill
						(type none)
					)
				)
				(polyline
					(pts
						(xy 3.302 1.016) (xy 3.302 -1.016) (xy 1.778 0) (xy 3.302 1.016)
					)
					(stroke
						(width 0.254)
						(type default)
					)
					(fill
						(type outline)
					)
				)
				(pin passive line
					(at 0 0 0)
					(length 0.635)
					(name "C"
						(effects
							(font
								(size 1.27 1.27)
							)
						)
					)
					(number "1"
						(effects
							(font
								(size 1.27 1.27)
							)
						)
					)
				)
				(pin passive line
					(at 5.08 0 180)
					(length 0.635)
					(name "A"
						(effects
							(font
								(size 1.27 1.27)
							)
						)
					)
					(number "2"
						(effects
							(font
								(size 1.27 1.27)
							)
						)
					)
				)
			)
		)
	(symbol "antmicroLEDIndicationDiscrete:LED_RGB_PLCC4_ASMB_MTB1_0A3A2"
			(exclude_from_sim no)
			(in_bom yes)
			(on_board yes)
			(property "Reference" "D"
				(at 27.94 -2.54 0)
				(effects
					(font
						(size 1.27 1.27)
					)
					(justify left bottom)
				)
			)
			(property "Value" "LED_RGB_PLCC4_ASMB_MTB1_0A3A2"
				(at 27.94 -7.62 0)
				(effects
					(font
						(size 1.27 1.27)
					)
					(justify left bottom)
					(hide yes)
				)
			)
			(property "Footprint" "antmicro-footprints:PLCC4_3.2x2.8mm"
				(at 27.94 -10.16 0)
				(effects
					(font
						(size 1.27 1.27)
					)
					(justify left bottom)
					(hide yes)
				)
			)
			(property "Datasheet" "https://docs.broadcom.com/doc/AV02-4194EN"
				(at 27.94 -12.7 0)
				(effects
					(font
						(size 1.27 1.27)
					)
					(justify left bottom)
					(hide yes)
				)
			)
			(property "Description" "LED, RGB, SMD, PLCC-4, R 20 mA, G 20 mA, B 20 mA, R 2.1 V, G 3.1 V, B 3.1 V, Common Anode"
				(at 0 0 0)
				(effects
					(font
						(size 1.27 1.27)
					)
					(hide yes)
				)
			)
			(property "MPN" "ASMB-MTB1-0A3A2"
				(at 27.94 -15.24 0)
				(effects
					(font
						(size 1.27 1.27)
					)
					(justify left bottom)
					(hide yes)
				)
			)
			(property "Manufacturer" "Avago Technologies"
				(at 27.94 -17.78 0)
				(effects
					(font
						(size 1.27 1.27)
					)
					(justify left bottom)
					(hide yes)
				)
			)
			(property "Color" "R, G, B"
				(at 27.94 -5.08 0)
				(effects
					(font
						(size 1.27 1.27)
					)
					(justify left bottom)
				)
			)
			(property "Author" "Antmicro"
				(at 27.94 -20.32 0)
				(effects
					(font
						(size 1.27 1.27)
					)
					(justify left bottom)
					(hide yes)
				)
			)
			(property "License" "Apache-2.0"
				(at 27.94 -22.86 0)
				(effects
					(font
						(size 1.27 1.27)
					)
					(justify left bottom)
					(hide yes)
				)
			)
			(property "ki_keywords" "SMT, DIODE, SEMICONDUCTOR, LED"
				(at 0 0 0)
				(effects
					(font
						(size 1.27 1.27)
					)
					(hide yes)
				)
			)
			(symbol "LED_RGB_PLCC4_ASMB_MTB1_0A3A2_1_1"
				(rectangle
					(start 2.54 -11.43)
					(end 16.51 3.81)
					(stroke
						(width 0.254)
						(type default)
					)
					(fill
						(type background)
					)
				)
				(polyline
					(pts
						(xy 6.35 0) (xy 8.89 0)
					)
					(stroke
						(width 0.254)
						(type default)
					)
					(fill
						(type none)
					)
				)
				(polyline
					(pts
						(xy 6.35 -3.81) (xy 8.89 -3.81)
					)
					(stroke
						(width 0.254)
						(type default)
					)
					(fill
						(type none)
					)
				)
				(polyline
					(pts
						(xy 6.35 -7.62) (xy 8.89 -7.62)
					)
					(stroke
						(width 0.254)
						(type default)
					)
					(fill
						(type none)
					)
				)
				(polyline
					(pts
						(xy 8.128 2.286) (xy 8.128 1.778) (xy 8.128 2.286) (xy 8.636 2.286) (xy 8.128 2.286) (xy 9.144 1.27)
					)
					(stroke
						(width 0.254)
						(type default)
					)
					(fill
						(type none)
					)
				)
				(polyline
					(pts
						(xy 8.128 -1.524) (xy 8.128 -2.032) (xy 8.128 -1.524) (xy 8.636 -1.524) (xy 8.128 -1.524) (xy 9.144 -2.54)
					)
					(stroke
						(width 0.254)
						(type default)
					)
					(fill
						(type none)
					)
				)
				(polyline
					(pts
						(xy 8.128 -5.334) (xy 8.128 -5.842) (xy 8.128 -5.334) (xy 8.636 -5.334) (xy 8.128 -5.334) (xy 9.144 -6.35)
					)
					(stroke
						(width 0.254)
						(type default)
					)
					(fill
						(type none)
					)
				)
				(polyline
					(pts
						(xy 8.763 1.016) (xy 8.763 -1.016)
					)
					(stroke
						(width 0.254)
						(type default)
					)
					(fill
						(type none)
					)
				)
				(polyline
					(pts
						(xy 8.763 -2.794) (xy 8.763 -4.826)
					)
					(stroke
						(width 0.254)
						(type default)
					)
					(fill
						(type none)
					)
				)
				(polyline
					(pts
						(xy 8.763 -6.604) (xy 8.763 -8.636)
					)
					(stroke
						(width 0.254)
						(type default)
					)
					(fill
						(type none)
					)
				)
				(polyline
					(pts
						(xy 9.144 2.54) (xy 9.144 2.032) (xy 9.144 2.54) (xy 9.652 2.54) (xy 9.144 2.54) (xy 10.033 1.651)
					)
					(stroke
						(width 0.254)
						(type default)
					)
					(fill
						(type none)
					)
				)
				(polyline
					(pts
						(xy 9.144 -1.27) (xy 9.144 -1.778) (xy 9.144 -1.27) (xy 9.652 -1.27) (xy 9.144 -1.27) (xy 10.033 -2.159)
					)
					(stroke
						(width 0.254)
						(type default)
					)
					(fill
						(type none)
					)
				)
				(polyline
					(pts
						(xy 9.144 -5.08) (xy 9.144 -5.588) (xy 9.144 -5.08) (xy 9.652 -5.08) (xy 9.144 -5.08) (xy 10.033 -5.969)
					)
					(stroke
						(width 0.254)
						(type default)
					)
					(fill
						(type none)
					)
				)
				(polyline
					(pts
						(xy 10.16 -3.81) (xy 12.7 -3.81) (xy 12.7 0) (xy 10.16 0)
					)
					(stroke
						(width 0.254)
						(type default)
					)
					(fill
						(type none)
					)
				)
				(polyline
					(pts
						(xy 10.287 1.016) (xy 10.287 -1.016) (xy 8.763 0) (xy 10.287 1.016)
					)
					(stroke
						(width 0.254)
						(type default)
					)
					(fill
						(type outline)
					)
				)
				(polyline
					(pts
						(xy 10.287 -2.794) (xy 10.287 -4.826) (xy 8.763 -3.81) (xy 10.287 -2.794)
					)
					(stroke
						(width 0.254)
						(type default)
					)
					(fill
						(type outline)
					)
				)
				(polyline
					(pts
						(xy 10.287 -6.604) (xy 10.287 -8.636) (xy 8.763 -7.62) (xy 10.287 -6.604)
					)
					(stroke
						(width 0.254)
						(type default)
					)
					(fill
						(type outline)
					)
				)
				(polyline
					(pts
						(xy 12.7 -3.81) (xy 13.97 -3.81)
					)
					(stroke
						(width 0.254)
						(type default)
					)
					(fill
						(type none)
					)
				)
				(polyline
					(pts
						(xy 12.7 -3.81) (xy 12.7 -7.62) (xy 10.16 -7.62)
					)
					(stroke
						(width 0.254)
						(type default)
					)
					(fill
						(type none)
					)
				)
				(pin passive line
					(at 0 0 0)
					(length 2.54)
					(name "C_{R}"
						(effects
							(font
								(size 1.27 1.27)
							)
						)
					)
					(number "1"
						(effects
							(font
								(size 1.27 1.27)
							)
						)
					)
				)
				(pin passive line
					(at 0 -3.81 0)
					(length 2.54)
					(name "C_{G}"
						(effects
							(font
								(size 1.27 1.27)
							)
						)
					)
					(number "2"
						(effects
							(font
								(size 1.27 1.27)
							)
						)
					)
				)
				(pin passive line
					(at 0 -7.62 0)
					(length 2.54)
					(name "C_{B}"
						(effects
							(font
								(size 1.27 1.27)
							)
						)
					)
					(number "3"
						(effects
							(font
								(size 1.27 1.27)
							)
						)
					)
				)
				(pin passive line
					(at 19.05 -3.81 180)
					(length 2.54)
					(name "A"
						(effects
							(font
								(size 1.27 1.27)
							)
						)
					)
					(number "4"
						(effects
							(font
								(size 1.27 1.27)
							)
						)
					)
				)
			)
		)
	(symbol "antmicroLogicGatesandInverters:74AUP2G132"
			(exclude_from_sim no)
			(in_bom yes)
			(on_board yes)
			(property "Reference" "U"
				(at 45.72 -5.08 0)
				(effects
					(font
						(size 1.27 1.27)
						(thickness 0.15)
					)
					(justify left bottom)
				)
			)
			(property "Value" "74AUP2G132"
				(at 45.72 -10.16 0)
				(effects
					(font
						(size 1.27 1.27)
						(thickness 0.15)
					)
					(justify left bottom)
					(hide yes)
				)
			)
			(property "Footprint" "antmicro-footprints:VSSOP-8_2.3x2mm_P0.5mm"
				(at 45.72 -12.7 0)
				(effects
					(font
						(size 1.27 1.27)
						(thickness 0.15)
					)
					(justify left bottom)
					(hide yes)
				)
			)
			(property "Datasheet" "https://assets.nexperia.com/documents/data-sheet/74AUP2G132.pdf"
				(at 45.72 -15.24 0)
				(effects
					(font
						(size 1.27 1.27)
						(thickness 0.15)
					)
					(justify left bottom)
					(hide yes)
				)
			)
			(property "Description" "Low-power dual 2-input NAND Schmitt trigger"
				(at 0 0 0)
				(effects
					(font
						(size 1.27 1.27)
					)
					(hide yes)
				)
			)
			(property "Manufacturer" "Nexperia"
				(at 45.72 -17.78 0)
				(effects
					(font
						(size 1.27 1.27)
						(thickness 0.15)
					)
					(justify left bottom)
					(hide yes)
				)
			)
			(property "MPN" "74AUP2G132"
				(at 45.72 -7.62 0)
				(effects
					(font
						(size 1.27 1.27)
						(thickness 0.15)
					)
					(justify left bottom)
				)
			)
			(property "Author" "Antmicro"
				(at 45.72 -20.32 0)
				(effects
					(font
						(size 1.27 1.27)
						(thickness 0.15)
					)
					(justify left bottom)
					(hide yes)
				)
			)
			(property "License" "Apache-2.0"
				(at 45.72 -22.86 0)
				(effects
					(font
						(size 1.27 1.27)
						(thickness 0.15)
					)
					(justify left bottom)
					(hide yes)
				)
			)
			(property "ki_keywords" "SMT, LOGIC, IC, GATE"
				(at 0 0 0)
				(effects
					(font
						(size 1.27 1.27)
					)
					(hide yes)
				)
			)
			(symbol "74AUP2G132_1_1"
				(rectangle
					(start 2.54 1.27)
					(end 15.24 -13.97)
					(stroke
						(width 0.254)
						(type default)
					)
					(fill
						(type background)
					)
				)
				(polyline
					(pts
						(xy 6.985 -3.048) (xy 6.477 -3.048)
					)
					(stroke
						(width 0.254)
						(type default)
					)
					(fill
						(type background)
					)
				)
				(polyline
					(pts
						(xy 6.985 -5.08) (xy 6.477 -5.08)
					)
					(stroke
						(width 0.254)
						(type default)
					)
					(fill
						(type background)
					)
				)
				(polyline
					(pts
						(xy 6.985 -8.128) (xy 6.477 -8.128)
					)
					(stroke
						(width 0.254)
						(type default)
					)
					(fill
						(type background)
					)
				)
				(polyline
					(pts
						(xy 6.985 -10.16) (xy 6.477 -10.16)
					)
					(stroke
						(width 0.254)
						(type default)
					)
					(fill
						(type background)
					)
				)
				(polyline
					(pts
						(xy 8.128 -3.429) (xy 8.128 -4.699)
					)
					(stroke
						(width 0.254)
						(type default)
					)
					(fill
						(type background)
					)
				)
				(polyline
					(pts
						(xy 8.128 -8.509) (xy 8.128 -9.779)
					)
					(stroke
						(width 0.254)
						(type default)
					)
					(fill
						(type background)
					)
				)
				(arc
					(start 10.0415 -4.0555)
					(mid 9.5919 -5.1386)
					(end 8.509 -5.588)
					(stroke
						(width 0.254)
						(type default)
					)
					(fill
						(type background)
					)
				)
				(arc
					(start 8.509 -2.54)
					(mid 9.5859 -2.9835)
					(end 10.0415 -4.0555)
					(stroke
						(width 0.254)
						(type default)
					)
					(fill
						(type background)
					)
				)
				(arc
					(start 10.0415 -9.1355)
					(mid 9.5919 -10.2186)
					(end 8.509 -10.668)
					(stroke
						(width 0.254)
						(type default)
					)
					(fill
						(type background)
					)
				)
				(arc
					(start 8.509 -7.62)
					(mid 9.5861 -8.0632)
					(end 10.0415 -9.1355)
					(stroke
						(width 0.254)
						(type default)
					)
					(fill
						(type background)
					)
				)
				(polyline
					(pts
						(xy 8.509 -2.54) (xy 6.985 -2.54) (xy 6.985 -5.588) (xy 8.509 -5.588)
					)
					(stroke
						(width 0.254)
						(type default)
					)
					(fill
						(type background)
					)
				)
				(polyline
					(pts
						(xy 8.509 -3.429) (xy 8.509 -4.699)
					)
					(stroke
						(width 0.254)
						(type default)
					)
					(fill
						(type background)
					)
				)
				(polyline
					(pts
						(xy 8.509 -4.699) (xy 7.62 -4.699)
					)
					(stroke
						(width 0.254)
						(type default)
					)
					(fill
						(type background)
					)
				)
				(polyline
					(pts
						(xy 8.509 -7.62) (xy 6.985 -7.62) (xy 6.985 -10.668) (xy 8.509 -10.668)
					)
					(stroke
						(width 0.254)
						(type default)
					)
					(fill
						(type background)
					)
				)
				(polyline
					(pts
						(xy 8.509 -8.509) (xy 8.509 -9.779)
					)
					(stroke
						(width 0.254)
						(type default)
					)
					(fill
						(type background)
					)
				)
				(polyline
					(pts
						(xy 8.509 -9.779) (xy 7.62 -9.779)
					)
					(stroke
						(width 0.254)
						(type default)
					)
					(fill
						(type background)
					)
				)
				(polyline
					(pts
						(xy 9.017 -3.429) (xy 8.128 -3.429)
					)
					(stroke
						(width 0.254)
						(type default)
					)
					(fill
						(type background)
					)
				)
				(polyline
					(pts
						(xy 9.017 -8.509) (xy 8.128 -8.509)
					)
					(stroke
						(width 0.254)
						(type default)
					)
					(fill
						(type background)
					)
				)
				(circle
					(center 10.287 -4.064)
					(radius 0.254)
					(stroke
						(width 0.254)
						(type default)
					)
					(fill
						(type background)
					)
				)
				(circle
					(center 10.287 -9.144)
					(radius 0.254)
					(stroke
						(width 0.254)
						(type default)
					)
					(fill
						(type background)
					)
				)
				(polyline
					(pts
						(xy 10.541 -9.144) (xy 11.176 -9.144) (xy 11.176 -7.874) (xy 11.557 -7.874)
					)
					(stroke
						(width 0.254)
						(type default)
					)
					(fill
						(type background)
					)
				)
				(polyline
					(pts
						(xy 10.668 -4.064) (xy 11.303 -4.064) (xy 11.303 -2.794) (xy 11.684 -2.794)
					)
					(stroke
						(width 0.254)
						(type default)
					)
					(fill
						(type background)
					)
				)
				(text ""
					(at 2.54 -3.048 0)
					(effects
						(font
							(size 1.27 1.27)
							(thickness 0.15)
						)
						(justify left bottom)
					)
				)
				(pin power_in line
					(at 0 0 0)
					(length 2.54)
					(name "VCC"
						(effects
							(font
								(size 1.27 1.27)
							)
						)
					)
					(number "8"
						(effects
							(font
								(size 1.27 1.27)
							)
						)
					)
				)
				(pin input line
					(at 0 -2.54 0)
					(length 2.54)
					(name "1A"
						(effects
							(font
								(size 1.27 1.27)
							)
						)
					)
					(number "1"
						(effects
							(font
								(size 1.27 1.27)
							)
						)
					)
				)
				(pin input line
					(at 0 -5.08 0)
					(length 2.54)
					(name "1B"
						(effects
							(font
								(size 1.27 1.27)
							)
						)
					)
					(number "2"
						(effects
							(font
								(size 1.27 1.27)
							)
						)
					)
				)
				(pin input line
					(at 0 -7.62 0)
					(length 2.54)
					(name "2A"
						(effects
							(font
								(size 1.27 1.27)
							)
						)
					)
					(number "5"
						(effects
							(font
								(size 1.27 1.27)
							)
						)
					)
				)
				(pin input line
					(at 0 -10.16 0)
					(length 2.54)
					(name "2B"
						(effects
							(font
								(size 1.27 1.27)
							)
						)
					)
					(number "6"
						(effects
							(font
								(size 1.27 1.27)
							)
						)
					)
				)
				(pin power_in line
					(at 0 -12.7 0)
					(length 2.54)
					(name "GND"
						(effects
							(font
								(size 1.27 1.27)
							)
						)
					)
					(number "4"
						(effects
							(font
								(size 1.27 1.27)
							)
						)
					)
				)
				(pin output line
					(at 17.78 -2.54 180)
					(length 2.54)
					(name "1Y"
						(effects
							(font
								(size 1.27 1.27)
							)
						)
					)
					(number "7"
						(effects
							(font
								(size 1.27 1.27)
							)
						)
					)
				)
				(pin output line
					(at 17.78 -7.62 180)
					(length 2.54)
					(name "2Y"
						(effects
							(font
								(size 1.27 1.27)
							)
						)
					)
					(number "3"
						(effects
							(font
								(size 1.27 1.27)
							)
						)
					)
				)
			)
		)
	(symbol "antmicroMechanicalParts:Lightpipe_Mentor_1296.2013"
			(exclude_from_sim no)
			(in_bom yes)
			(on_board yes)
			(property "Reference" "H"
				(at 20.32 -2.54 0)
				(effects
					(font
						(size 1.27 1.27)
						(thickness 0.15)
					)
					(justify left bottom)
				)
			)
			(property "Value" "Lightpipe_Mentor_1296.2013"
				(at 20.32 -5.08 0)
				(effects
					(font
						(size 1.27 1.27)
						(thickness 0.15)
					)
					(justify left bottom)
				)
			)
			(property "Footprint" "antmicro-footprints:Mech_Lightpipe_Mentor_1296.2013"
				(at 20.32 -7.62 0)
				(effects
					(font
						(size 1.27 1.27)
						(thickness 0.15)
					)
					(justify left bottom)
					(hide yes)
				)
			)
			(property "Datasheet" "https://docs.rs-online.com/e47b/0900766b813f6efb.pdf"
				(at 20.32 -10.16 0)
				(effects
					(font
						(size 1.27 1.27)
						(thickness 0.15)
					)
					(justify left bottom)
					(hide yes)
				)
			)
			(property "Description" "Light Pipe, Miniature Triple Line, 14.45 mm, 3 Pipes, Circular, PC Board, Transparent"
				(at 0 0 0)
				(effects
					(font
						(size 1.27 1.27)
					)
					(hide yes)
				)
			)
			(property "Manufacturer" "Mentor Worldwide"
				(at 20.32 -12.7 0)
				(effects
					(font
						(size 1.27 1.27)
						(thickness 0.15)
					)
					(justify left bottom)
					(hide yes)
				)
			)
			(property "MPN" "1296.2013"
				(at 20.32 -15.24 0)
				(effects
					(font
						(size 1.27 1.27)
						(thickness 0.15)
					)
					(justify left bottom)
					(hide yes)
				)
			)
			(property "Author" "Antmicro"
				(at 20.32 -17.78 0)
				(effects
					(font
						(size 1.27 1.27)
						(thickness 0.15)
					)
					(justify left bottom)
					(hide yes)
				)
			)
			(property "License" "Apache-2.0"
				(at 20.32 -20.32 0)
				(effects
					(font
						(size 1.27 1.27)
						(thickness 0.15)
					)
					(justify left bottom)
					(hide yes)
				)
			)
			(property "ki_keywords" "HORIZONTAL, THT, MECHANICAL, MODULE"
				(at 0 0 0)
				(effects
					(font
						(size 1.27 1.27)
					)
					(hide yes)
				)
			)
			(symbol "Lightpipe_Mentor_1296.2013_1_1"
				(rectangle
					(start 5.08 -2.54)
					(end -5.08 3.81)
					(stroke
						(width 0.254)
						(type default)
					)
					(fill
						(type background)
					)
				)
				(text "Horizontal"
					(at -5.08 1.524 0)
					(effects
						(font
							(size 1.27 1.27)
							(thickness 0.15)
						)
						(justify left bottom)
					)
				)
				(text "lightguide"
					(at -4.826 -0.508 0)
					(effects
						(font
							(size 1.27 1.27)
							(thickness 0.15)
						)
						(justify left bottom)
					)
				)
				(text "1x3"
					(at -1.905 -2.54 0)
					(effects
						(font
							(size 1.27 1.27)
							(thickness 0.15)
						)
						(justify left bottom)
					)
				)
			)
		)
	(symbol "antmicroMechanicalParts:MP_Pad6mm_Drill3.2mm"
			(pin_names
				(hide yes)
			)
			(exclude_from_sim no)
			(in_bom no)
			(on_board yes)
			(property "Reference" "MP"
				(at 20.32 -2.54 0)
				(effects
					(font
						(size 1.27 1.27)
						(thickness 0.15)
					)
					(justify left bottom)
				)
			)
			(property "Value" "MP_Pad6mm_Drill3.2mm"
				(at 20.32 -5.08 0)
				(effects
					(font
						(size 1.27 1.27)
						(thickness 0.15)
					)
					(justify left bottom)
				)
			)
			(property "Footprint" "antmicro-footprints:MP_Pad6mm_Drill3.2mm"
				(at 20.32 -7.62 0)
				(effects
					(font
						(size 1.27 1.27)
						(thickness 0.15)
					)
					(justify left bottom)
					(hide yes)
				)
			)
			(property "Datasheet" ""
				(at 16.84 -15.57 0)
				(effects
					(font
						(size 1.27 1.27)
						(thickness 0.15)
					)
					(justify left bottom)
					(hide yes)
				)
			)
			(property "Description" "Mechanical part"
				(at 0 0 0)
				(effects
					(font
						(size 1.27 1.27)
					)
					(hide yes)
				)
			)
			(property "Author" "Antmicro"
				(at 20.32 -10.16 0)
				(effects
					(font
						(size 1.27 1.27)
						(thickness 0.15)
					)
					(justify left bottom)
					(hide yes)
				)
			)
			(property "License" "Apache-2.0"
				(at 20.32 -12.7 0)
				(effects
					(font
						(size 1.27 1.27)
						(thickness 0.15)
					)
					(justify left bottom)
					(hide yes)
				)
			)
			(property "ki_keywords" "MECHANICAL"
				(at 0 0 0)
				(effects
					(font
						(size 1.27 1.27)
					)
					(hide yes)
				)
			)
			(symbol "MP_Pad6mm_Drill3.2mm_1_1"
				(circle
					(center 5.08 0)
					(radius 1.27)
					(stroke
						(width 0.254)
						(type default)
					)
					(fill
						(type background)
					)
				)
				(circle
					(center 5.08 0)
					(radius 2.54)
					(stroke
						(width 0.254)
						(type default)
					)
					(fill
						(type background)
					)
				)
				(pin passive line
					(at 0 0 0)
					(length 2.54)
					(name "~"
						(effects
							(font
								(size 1.27 1.27)
							)
						)
					)
					(number "1"
						(effects
							(font
								(size 1.27 1.27)
							)
						)
					)
				)
			)
		)
	(symbol "antmicroPMICORControllersIdealDiodes:LTC4412IS6"
			(exclude_from_sim no)
			(in_bom yes)
			(on_board yes)
			(property "Reference" "U"
				(at 31.75 -2.54 0)
				(effects
					(font
						(size 1.27 1.27)
						(thickness 0.15)
					)
					(justify left bottom)
				)
			)
			(property "Value" "LTC4412IS6"
				(at 31.75 -5.08 0)
				(effects
					(font
						(size 1.27 1.27)
						(thickness 0.15)
					)
					(justify left bottom)
					(hide yes)
				)
			)
			(property "Footprint" "antmicro-footprints:SOT-23-6"
				(at 31.75 -7.62 0)
				(effects
					(font
						(size 1.27 1.27)
						(thickness 0.15)
					)
					(justify left bottom)
					(hide yes)
				)
			)
			(property "Datasheet" "https://www.analog.com/media/en/technical-documentation/data-sheets/4412fb.pdf"
				(at 31.75 -10.16 0)
				(effects
					(font
						(size 1.27 1.27)
						(thickness 0.15)
					)
					(justify left bottom)
					(hide yes)
				)
			)
			(property "Description" "Ideal diode controller"
				(at 0 0 0)
				(effects
					(font
						(size 1.27 1.27)
					)
					(hide yes)
				)
			)
			(property "MPN" "LTC4412IS6#TRMPBF"
				(at 31.75 -12.7 0)
				(effects
					(font
						(size 1.27 1.27)
						(thickness 0.15)
					)
					(justify left bottom)
				)
			)
			(property "Manufacturer" "Analog Devices"
				(at 31.75 -15.24 0)
				(effects
					(font
						(size 1.27 1.27)
						(thickness 0.15)
					)
					(justify left bottom)
					(hide yes)
				)
			)
			(property "Author" "Antmicro"
				(at 31.75 -17.78 0)
				(effects
					(font
						(size 1.27 1.27)
						(thickness 0.15)
					)
					(justify left bottom)
					(hide yes)
				)
			)
			(property "License" "Apache-2.0"
				(at 31.75 -20.32 0)
				(effects
					(font
						(size 1.27 1.27)
						(thickness 0.15)
					)
					(justify left bottom)
					(hide yes)
				)
			)
			(property "ki_keywords" "SMT, CONTROLLER, IC, DIODE"
				(at 0 0 0)
				(effects
					(font
						(size 1.27 1.27)
					)
					(hide yes)
				)
			)
			(symbol "LTC4412IS6_1_1"
				(rectangle
					(start 2.54 2.54)
					(end 15.24 -7.62)
					(stroke
						(width 0.254)
						(type default)
					)
					(fill
						(type background)
					)
				)
				(pin power_in line
					(at 0 0 0)
					(length 2.54)
					(name "IN"
						(effects
							(font
								(size 1.27 1.27)
							)
						)
					)
					(number "1"
						(effects
							(font
								(size 1.27 1.27)
							)
						)
					)
				)
				(pin input line
					(at 0 -2.54 0)
					(length 2.54)
					(name "CTL"
						(effects
							(font
								(size 1.27 1.27)
							)
						)
					)
					(number "3"
						(effects
							(font
								(size 1.27 1.27)
							)
						)
					)
				)
				(pin power_in line
					(at 0 -5.08 0)
					(length 2.54)
					(name "GND"
						(effects
							(font
								(size 1.27 1.27)
							)
						)
					)
					(number "2"
						(effects
							(font
								(size 1.27 1.27)
							)
						)
					)
				)
				(pin input line
					(at 17.78 0 180)
					(length 2.54)
					(name "SENSE"
						(effects
							(font
								(size 1.27 1.27)
							)
						)
					)
					(number "6"
						(effects
							(font
								(size 1.27 1.27)
							)
						)
					)
				)
				(pin output line
					(at 17.78 -2.54 180)
					(length 2.54)
					(name "GATE"
						(effects
							(font
								(size 1.27 1.27)
							)
						)
					)
					(number "5"
						(effects
							(font
								(size 1.27 1.27)
							)
						)
					)
				)
				(pin output line
					(at 17.78 -5.08 180)
					(length 2.54)
					(name "STAT"
						(effects
							(font
								(size 1.27 1.27)
							)
						)
					)
					(number "4"
						(effects
							(font
								(size 1.27 1.27)
							)
						)
					)
				)
			)
		)
	(symbol "antmicroPciConnectors:OCuLink_x4_Amphenol_G14A421211112HR_CUSTOM_device_side"
			(exclude_from_sim no)
			(in_bom yes)
			(on_board yes)
			(property "Reference" "J"
				(at 39.37 -5.08 0)
				(effects
					(font
						(size 1.27 1.27)
						(thickness 0.15)
					)
					(justify left bottom)
				)
			)
			(property "Value" "OCuLink_x4_Amphenol_G14A421211112HR_CUSTOM_device_side"
				(at 39.37 -12.7 0)
				(effects
					(font
						(size 1.27 1.27)
						(thickness 0.15)
					)
					(justify left bottom)
					(hide yes)
				)
			)
			(property "Footprint" "antmicro-footprints:Amphenol_G14A421211112HR"
				(at 39.37 -15.24 0)
				(effects
					(font
						(size 1.27 1.27)
						(thickness 0.15)
					)
					(justify left bottom)
					(hide yes)
				)
			)
			(property "Datasheet" "https://cdn.amphenol-cs.com/media/wysiwyg/files/drawing/g14a421x1bxxxhr.pdf"
				(at 39.37 -17.78 0)
				(effects
					(font
						(size 1.27 1.27)
						(thickness 0.15)
					)
					(justify left bottom)
					(hide yes)
				)
			)
			(property "Description" "I/O Connectors OCulink, Receptacle, 0.5mm pitch, 4X, R/A SMT with shell leg SMT type, 30U\" gold plating, LCP, black, T&R packing"
				(at 0 0 0)
				(effects
					(font
						(size 1.27 1.27)
					)
					(hide yes)
				)
			)
			(property "Manufacturer" "Amphenol"
				(at 39.37 -10.16 0)
				(effects
					(font
						(size 1.27 1.27)
						(thickness 0.15)
					)
					(justify left bottom)
					(hide yes)
				)
			)
			(property "MPN" "G14A421211112HR"
				(at 39.37 -7.62 0)
				(effects
					(font
						(size 1.27 1.27)
						(thickness 0.15)
					)
					(justify left bottom)
				)
			)
			(property "Author" "Antmicro"
				(at 39.37 -20.32 0)
				(effects
					(font
						(size 1.27 1.27)
						(thickness 0.15)
					)
					(justify left bottom)
					(hide yes)
				)
			)
			(property "License" "Apache-2.0"
				(at 39.37 -22.86 0)
				(effects
					(font
						(size 1.27 1.27)
						(thickness 0.15)
					)
					(justify left bottom)
					(hide yes)
				)
			)
			(property "ki_keywords" "SMT, CONNECTOR, PCIE"
				(at 0 0 0)
				(effects
					(font
						(size 1.27 1.27)
					)
					(hide yes)
				)
			)
			(symbol "OCuLink_x4_Amphenol_G14A421211112HR_CUSTOM_device_side_1_1"
				(rectangle
					(start 3.81 2.54)
					(end 21.59 -93.98)
					(stroke
						(width 0.254)
						(type default)
					)
					(fill
						(type background)
					)
				)
				(pin passive line
					(at 0 0 0)
					(length 3.81)
					(name "5V"
						(effects
							(font
								(size 1.27 1.27)
							)
						)
					)
					(number "A21"
						(effects
							(font
								(size 1.27 1.27)
							)
						)
					)
				)
				(pin passive line
					(at 0 0 0)
					(length 3.81)
					(hide yes)
					(name "5V"
						(effects
							(font
								(size 1.27 1.27)
							)
						)
					)
					(number "B1"
						(effects
							(font
								(size 1.27 1.27)
							)
						)
					)
				)
				(pin power_in line
					(at 0 -2.54 0)
					(length 3.81)
					(name "V_{ACT}_RX_3V3"
						(effects
							(font
								(size 1.27 1.27)
							)
						)
					)
					(number "A1"
						(effects
							(font
								(size 1.27 1.27)
							)
						)
					)
				)
				(pin power_in line
					(at 0 -5.08 0)
					(length 3.81)
					(name "V_{ACT}_TX_3V3"
						(effects
							(font
								(size 1.27 1.27)
							)
						)
					)
					(number "B21"
						(effects
							(font
								(size 1.27 1.27)
							)
						)
					)
				)
				(pin bidirectional line
					(at 0 -10.16 0)
					(length 3.81)
					(name "SCL"
						(effects
							(font
								(size 1.27 1.27)
							)
						)
					)
					(number "A9"
						(effects
							(font
								(size 1.27 1.27)
							)
						)
					)
				)
				(pin bidirectional line
					(at 0 -12.7 0)
					(length 3.81)
					(name "SDA"
						(effects
							(font
								(size 1.27 1.27)
							)
						)
					)
					(number "A10"
						(effects
							(font
								(size 1.27 1.27)
							)
						)
					)
				)
				(pin bidirectional line
					(at 0 -17.78 0)
					(length 3.81)
					(name "VSP1"
						(effects
							(font
								(size 1.27 1.27)
							)
						)
					)
					(number "B12"
						(effects
							(font
								(size 1.27 1.27)
							)
						)
					)
				)
				(pin bidirectional line
					(at 0 -20.32 0)
					(length 3.81)
					(name "VSP2"
						(effects
							(font
								(size 1.27 1.27)
							)
						)
					)
					(number "B13"
						(effects
							(font
								(size 1.27 1.27)
							)
						)
					)
				)
				(pin bidirectional line
					(at 0 -25.4 0)
					(length 3.81)
					(name "~{PERST}"
						(effects
							(font
								(size 1.27 1.27)
							)
						)
					)
					(number "A12"
						(effects
							(font
								(size 1.27 1.27)
							)
						)
					)
				)
				(pin bidirectional line
					(at 0 -27.94 0)
					(length 3.81)
					(name "~{CPRSNT}"
						(effects
							(font
								(size 1.27 1.27)
							)
						)
					)
					(number "A13"
						(effects
							(font
								(size 1.27 1.27)
							)
						)
					)
				)
				(pin bidirectional line
					(at 0 -30.48 0)
					(length 3.81)
					(name "~{CWAKE}"
						(effects
							(font
								(size 1.27 1.27)
							)
						)
					)
					(number "B10"
						(effects
							(font
								(size 1.27 1.27)
							)
						)
					)
				)
				(pin input line
					(at 0 -35.56 0)
					(length 3.81)
					(name "PET0+"
						(effects
							(font
								(size 1.27 1.27)
							)
						)
					)
					(number "B3"
						(effects
							(font
								(size 1.27 1.27)
							)
						)
					)
				)
				(pin input line
					(at 0 -38.1 0)
					(length 3.81)
					(name "PET0-"
						(effects
							(font
								(size 1.27 1.27)
							)
						)
					)
					(number "B4"
						(effects
							(font
								(size 1.27 1.27)
							)
						)
					)
				)
				(pin input line
					(at 0 -43.18 0)
					(length 3.81)
					(name "PET1+"
						(effects
							(font
								(size 1.27 1.27)
							)
						)
					)
					(number "B6"
						(effects
							(font
								(size 1.27 1.27)
							)
						)
					)
				)
				(pin input line
					(at 0 -45.72 0)
					(length 3.81)
					(name "PET1-"
						(effects
							(font
								(size 1.27 1.27)
							)
						)
					)
					(number "B7"
						(effects
							(font
								(size 1.27 1.27)
							)
						)
					)
				)
				(pin input line
					(at 0 -50.8 0)
					(length 3.81)
					(name "PET2+"
						(effects
							(font
								(size 1.27 1.27)
							)
						)
					)
					(number "B15"
						(effects
							(font
								(size 1.27 1.27)
							)
						)
					)
				)
				(pin input line
					(at 0 -53.34 0)
					(length 3.81)
					(name "PET2-"
						(effects
							(font
								(size 1.27 1.27)
							)
						)
					)
					(number "B16"
						(effects
							(font
								(size 1.27 1.27)
							)
						)
					)
				)
				(pin input line
					(at 0 -58.42 0)
					(length 3.81)
					(name "PET3+"
						(effects
							(font
								(size 1.27 1.27)
							)
						)
					)
					(number "B18"
						(effects
							(font
								(size 1.27 1.27)
							)
						)
					)
				)
				(pin input line
					(at 0 -60.96 0)
					(length 3.81)
					(name "PET3-"
						(effects
							(font
								(size 1.27 1.27)
							)
						)
					)
					(number "B19"
						(effects
							(font
								(size 1.27 1.27)
							)
						)
					)
				)
				(pin output line
					(at 0 -66.04 0)
					(length 3.81)
					(name "PER0+"
						(effects
							(font
								(size 1.27 1.27)
							)
						)
					)
					(number "A3"
						(effects
							(font
								(size 1.27 1.27)
							)
						)
					)
				)
				(pin output line
					(at 0 -68.58 0)
					(length 3.81)
					(name "PER0-"
						(effects
							(font
								(size 1.27 1.27)
							)
						)
					)
					(number "A4"
						(effects
							(font
								(size 1.27 1.27)
							)
						)
					)
				)
				(pin output line
					(at 0 -73.66 0)
					(length 3.81)
					(name "PER1+"
						(effects
							(font
								(size 1.27 1.27)
							)
						)
					)
					(number "A6"
						(effects
							(font
								(size 1.27 1.27)
							)
						)
					)
				)
				(pin output line
					(at 0 -76.2 0)
					(length 3.81)
					(name "PER1-"
						(effects
							(font
								(size 1.27 1.27)
							)
						)
					)
					(number "A7"
						(effects
							(font
								(size 1.27 1.27)
							)
						)
					)
				)
				(pin output line
					(at 0 -81.28 0)
					(length 3.81)
					(name "PER2+"
						(effects
							(font
								(size 1.27 1.27)
							)
						)
					)
					(number "A15"
						(effects
							(font
								(size 1.27 1.27)
							)
						)
					)
				)
				(pin output line
					(at 0 -83.82 0)
					(length 3.81)
					(name "PER2-"
						(effects
							(font
								(size 1.27 1.27)
							)
						)
					)
					(number "A16"
						(effects
							(font
								(size 1.27 1.27)
							)
						)
					)
				)
				(pin output line
					(at 0 -88.9 0)
					(length 3.81)
					(name "PER3+"
						(effects
							(font
								(size 1.27 1.27)
							)
						)
					)
					(number "A18"
						(effects
							(font
								(size 1.27 1.27)
							)
						)
					)
				)
				(pin output line
					(at 0 -91.44 0)
					(length 3.81)
					(name "PER3-"
						(effects
							(font
								(size 1.27 1.27)
							)
						)
					)
					(number "A19"
						(effects
							(font
								(size 1.27 1.27)
							)
						)
					)
				)
				(pin no_connect line
					(at 21.59 -76.2 180)
					(length 3.81)
					(hide yes)
					(name "NC"
						(effects
							(font
								(size 1.27 1.27)
							)
						)
					)
					(number "B9"
						(effects
							(font
								(size 1.27 1.27)
							)
						)
					)
				)
				(pin passive line
					(at 25.4 -88.9 180)
					(length 3.81)
					(name "SH"
						(effects
							(font
								(size 1.27 1.27)
							)
						)
					)
					(number "SH"
						(effects
							(font
								(size 1.27 1.27)
							)
						)
					)
				)
				(pin passive line
					(at 25.4 -91.44 180)
					(length 3.81)
					(name "GND"
						(effects
							(font
								(size 1.27 1.27)
							)
						)
					)
					(number "A11"
						(effects
							(font
								(size 1.27 1.27)
							)
						)
					)
				)
				(pin passive line
					(at 25.4 -91.44 180)
					(length 3.81)
					(hide yes)
					(name "GND"
						(effects
							(font
								(size 1.27 1.27)
							)
						)
					)
					(number "A14"
						(effects
							(font
								(size 1.27 1.27)
							)
						)
					)
				)
				(pin passive line
					(at 25.4 -91.44 180)
					(length 3.81)
					(hide yes)
					(name "GND"
						(effects
							(font
								(size 1.27 1.27)
							)
						)
					)
					(number "A17"
						(effects
							(font
								(size 1.27 1.27)
							)
						)
					)
				)
				(pin passive line
					(at 25.4 -91.44 180)
					(length 3.81)
					(hide yes)
					(name "GND"
						(effects
							(font
								(size 1.27 1.27)
							)
						)
					)
					(number "A2"
						(effects
							(font
								(size 1.27 1.27)
							)
						)
					)
				)
				(pin passive line
					(at 25.4 -91.44 180)
					(length 3.81)
					(hide yes)
					(name "GND"
						(effects
							(font
								(size 1.27 1.27)
							)
						)
					)
					(number "A20"
						(effects
							(font
								(size 1.27 1.27)
							)
						)
					)
				)
				(pin passive line
					(at 25.4 -91.44 180)
					(length 3.81)
					(hide yes)
					(name "GND"
						(effects
							(font
								(size 1.27 1.27)
							)
						)
					)
					(number "A5"
						(effects
							(font
								(size 1.27 1.27)
							)
						)
					)
				)
				(pin passive line
					(at 25.4 -91.44 180)
					(length 3.81)
					(hide yes)
					(name "GND"
						(effects
							(font
								(size 1.27 1.27)
							)
						)
					)
					(number "A8"
						(effects
							(font
								(size 1.27 1.27)
							)
						)
					)
				)
				(pin passive line
					(at 25.4 -91.44 180)
					(length 3.81)
					(hide yes)
					(name "GND"
						(effects
							(font
								(size 1.27 1.27)
							)
						)
					)
					(number "B11"
						(effects
							(font
								(size 1.27 1.27)
							)
						)
					)
				)
				(pin passive line
					(at 25.4 -91.44 180)
					(length 3.81)
					(hide yes)
					(name "GND"
						(effects
							(font
								(size 1.27 1.27)
							)
						)
					)
					(number "B14"
						(effects
							(font
								(size 1.27 1.27)
							)
						)
					)
				)
				(pin passive line
					(at 25.4 -91.44 180)
					(length 3.81)
					(hide yes)
					(name "GND"
						(effects
							(font
								(size 1.27 1.27)
							)
						)
					)
					(number "B17"
						(effects
							(font
								(size 1.27 1.27)
							)
						)
					)
				)
				(pin passive line
					(at 25.4 -91.44 180)
					(length 3.81)
					(hide yes)
					(name "GND"
						(effects
							(font
								(size 1.27 1.27)
							)
						)
					)
					(number "B2"
						(effects
							(font
								(size 1.27 1.27)
							)
						)
					)
				)
				(pin passive line
					(at 25.4 -91.44 180)
					(length 3.81)
					(hide yes)
					(name "GND"
						(effects
							(font
								(size 1.27 1.27)
							)
						)
					)
					(number "B20"
						(effects
							(font
								(size 1.27 1.27)
							)
						)
					)
				)
				(pin passive line
					(at 25.4 -91.44 180)
					(length 3.81)
					(hide yes)
					(name "GND"
						(effects
							(font
								(size 1.27 1.27)
							)
						)
					)
					(number "B5"
						(effects
							(font
								(size 1.27 1.27)
							)
						)
					)
				)
				(pin passive line
					(at 25.4 -91.44 180)
					(length 3.81)
					(hide yes)
					(name "GND"
						(effects
							(font
								(size 1.27 1.27)
							)
						)
					)
					(number "B8"
						(effects
							(font
								(size 1.27 1.27)
							)
						)
					)
				)
			)
		)
	(symbol "antmicroPciConnectors:PCIe_x16_10146070-113Y0LF-vertical"
			(exclude_from_sim no)
			(in_bom yes)
			(on_board yes)
			(property "Reference" "J"
				(at 35.56 -2.54 0)
				(effects
					(font
						(size 1.27 1.27)
						(thickness 0.15)
					)
					(justify left bottom)
				)
			)
			(property "Value" "PCIe_x16_10146070-113Y0LF-vertical"
				(at 35.56 -5.08 0)
				(effects
					(font
						(size 1.27 1.27)
						(thickness 0.15)
					)
					(justify left bottom)
					(hide yes)
				)
			)
			(property "Footprint" "antmicro-footprints:AMPHENOL_10146070-113Y0LF"
				(at 35.56 -7.62 0)
				(effects
					(font
						(size 1.27 1.27)
						(thickness 0.15)
					)
					(justify left bottom)
					(hide yes)
				)
			)
			(property "Datasheet" "https://www.farnell.com/datasheets/3212936.pdf"
				(at 35.56 -10.16 0)
				(effects
					(font
						(size 1.27 1.27)
						(thickness 0.15)
					)
					(justify left bottom)
					(hide yes)
				)
			)
			(property "Description" "164 Position Female Connector PCI Express™ Gold 0.039\" (1.00mm) Black"
				(at 0 0 0)
				(effects
					(font
						(size 1.27 1.27)
					)
					(hide yes)
				)
			)
			(property "PARTREV" "E"
				(at 35.56 -12.7 0)
				(effects
					(font
						(size 1.27 1.27)
						(thickness 0.15)
					)
					(justify left bottom)
					(hide yes)
				)
			)
			(property "STANDARD" "Manufacturer Recommendations"
				(at 35.56 -15.24 0)
				(effects
					(font
						(size 1.27 1.27)
						(thickness 0.15)
					)
					(justify left bottom)
					(hide yes)
				)
			)
			(property "MAXIMUM_PACKAGE_HEIGHT" "11.25mm"
				(at 35.56 -17.78 0)
				(effects
					(font
						(size 1.27 1.27)
						(thickness 0.15)
					)
					(justify left bottom)
					(hide yes)
				)
			)
			(property "Manufacturer" "Amphenol"
				(at 35.56 -20.32 0)
				(effects
					(font
						(size 1.27 1.27)
						(thickness 0.15)
					)
					(justify left bottom)
					(hide yes)
				)
			)
			(property "Author" "Antmicro"
				(at 35.56 -22.86 0)
				(effects
					(font
						(size 1.27 1.27)
						(thickness 0.15)
					)
					(justify left bottom)
					(hide yes)
				)
			)
			(property "License" "Apache-2.0"
				(at 35.56 -25.4 0)
				(effects
					(font
						(size 1.27 1.27)
						(thickness 0.15)
					)
					(justify left bottom)
					(hide yes)
				)
			)
			(property "MPN" "10146070-113Y0LF"
				(at 35.56 -27.94 0)
				(effects
					(font
						(size 1.27 1.27)
						(thickness 0.15)
					)
					(justify left bottom)
				)
			)
			(property "ki_keywords" "CONNECTOR"
				(at 0 0 0)
				(effects
					(font
						(size 1.27 1.27)
					)
					(hide yes)
				)
			)
			(symbol "PCIe_x16_10146070-113Y0LF-vertical_1_1"
				(rectangle
					(start 3.81 -104.14)
					(end 19.05 2.54)
					(stroke
						(width 0.254)
						(type default)
					)
					(fill
						(type background)
					)
				)
				(pin passive line
					(at 0 0 0)
					(length 3.81)
					(name "B1"
						(effects
							(font
								(size 1.27 1.27)
							)
						)
					)
					(number "B1"
						(effects
							(font
								(size 1.27 1.27)
							)
						)
					)
				)
				(pin passive line
					(at 0 -2.54 0)
					(length 3.81)
					(name "B2"
						(effects
							(font
								(size 1.27 1.27)
							)
						)
					)
					(number "B2"
						(effects
							(font
								(size 1.27 1.27)
							)
						)
					)
				)
				(pin passive line
					(at 0 -5.08 0)
					(length 3.81)
					(name "B3"
						(effects
							(font
								(size 1.27 1.27)
							)
						)
					)
					(number "B3"
						(effects
							(font
								(size 1.27 1.27)
							)
						)
					)
				)
				(pin passive line
					(at 0 -7.62 0)
					(length 3.81)
					(name "B4"
						(effects
							(font
								(size 1.27 1.27)
							)
						)
					)
					(number "B4"
						(effects
							(font
								(size 1.27 1.27)
							)
						)
					)
				)
				(pin passive line
					(at 0 -10.16 0)
					(length 3.81)
					(name "B5"
						(effects
							(font
								(size 1.27 1.27)
							)
						)
					)
					(number "B5"
						(effects
							(font
								(size 1.27 1.27)
							)
						)
					)
				)
				(pin passive line
					(at 0 -12.7 0)
					(length 3.81)
					(name "B6"
						(effects
							(font
								(size 1.27 1.27)
							)
						)
					)
					(number "B6"
						(effects
							(font
								(size 1.27 1.27)
							)
						)
					)
				)
				(pin passive line
					(at 0 -15.24 0)
					(length 3.81)
					(name "B7"
						(effects
							(font
								(size 1.27 1.27)
							)
						)
					)
					(number "B7"
						(effects
							(font
								(size 1.27 1.27)
							)
						)
					)
				)
				(pin passive line
					(at 0 -17.78 0)
					(length 3.81)
					(name "B8"
						(effects
							(font
								(size 1.27 1.27)
							)
						)
					)
					(number "B8"
						(effects
							(font
								(size 1.27 1.27)
							)
						)
					)
				)
				(pin passive line
					(at 0 -20.32 0)
					(length 3.81)
					(name "B9"
						(effects
							(font
								(size 1.27 1.27)
							)
						)
					)
					(number "B9"
						(effects
							(font
								(size 1.27 1.27)
							)
						)
					)
				)
				(pin passive line
					(at 0 -22.86 0)
					(length 3.81)
					(name "B10"
						(effects
							(font
								(size 1.27 1.27)
							)
						)
					)
					(number "B10"
						(effects
							(font
								(size 1.27 1.27)
							)
						)
					)
				)
				(pin passive line
					(at 0 -25.4 0)
					(length 3.81)
					(name "B11"
						(effects
							(font
								(size 1.27 1.27)
							)
						)
					)
					(number "B11"
						(effects
							(font
								(size 1.27 1.27)
							)
						)
					)
				)
				(pin passive line
					(at 0 -27.94 0)
					(length 3.81)
					(name "B12"
						(effects
							(font
								(size 1.27 1.27)
							)
						)
					)
					(number "B12"
						(effects
							(font
								(size 1.27 1.27)
							)
						)
					)
				)
				(pin passive line
					(at 0 -30.48 0)
					(length 3.81)
					(name "B13"
						(effects
							(font
								(size 1.27 1.27)
							)
						)
					)
					(number "B13"
						(effects
							(font
								(size 1.27 1.27)
							)
						)
					)
				)
				(pin passive line
					(at 0 -33.02 0)
					(length 3.81)
					(name "B14"
						(effects
							(font
								(size 1.27 1.27)
							)
						)
					)
					(number "B14"
						(effects
							(font
								(size 1.27 1.27)
							)
						)
					)
				)
				(pin passive line
					(at 0 -35.56 0)
					(length 3.81)
					(name "B15"
						(effects
							(font
								(size 1.27 1.27)
							)
						)
					)
					(number "B15"
						(effects
							(font
								(size 1.27 1.27)
							)
						)
					)
				)
				(pin passive line
					(at 0 -38.1 0)
					(length 3.81)
					(name "B16"
						(effects
							(font
								(size 1.27 1.27)
							)
						)
					)
					(number "B16"
						(effects
							(font
								(size 1.27 1.27)
							)
						)
					)
				)
				(pin passive line
					(at 0 -40.64 0)
					(length 3.81)
					(name "B17"
						(effects
							(font
								(size 1.27 1.27)
							)
						)
					)
					(number "B17"
						(effects
							(font
								(size 1.27 1.27)
							)
						)
					)
				)
				(pin passive line
					(at 0 -43.18 0)
					(length 3.81)
					(name "B18"
						(effects
							(font
								(size 1.27 1.27)
							)
						)
					)
					(number "B18"
						(effects
							(font
								(size 1.27 1.27)
							)
						)
					)
				)
				(pin passive line
					(at 0 -45.72 0)
					(length 3.81)
					(name "B19"
						(effects
							(font
								(size 1.27 1.27)
							)
						)
					)
					(number "B19"
						(effects
							(font
								(size 1.27 1.27)
							)
						)
					)
				)
				(pin passive line
					(at 0 -48.26 0)
					(length 3.81)
					(name "B20"
						(effects
							(font
								(size 1.27 1.27)
							)
						)
					)
					(number "B20"
						(effects
							(font
								(size 1.27 1.27)
							)
						)
					)
				)
				(pin passive line
					(at 0 -50.8 0)
					(length 3.81)
					(name "B21"
						(effects
							(font
								(size 1.27 1.27)
							)
						)
					)
					(number "B21"
						(effects
							(font
								(size 1.27 1.27)
							)
						)
					)
				)
				(pin passive line
					(at 0 -53.34 0)
					(length 3.81)
					(name "B22"
						(effects
							(font
								(size 1.27 1.27)
							)
						)
					)
					(number "B22"
						(effects
							(font
								(size 1.27 1.27)
							)
						)
					)
				)
				(pin passive line
					(at 0 -55.88 0)
					(length 3.81)
					(name "B23"
						(effects
							(font
								(size 1.27 1.27)
							)
						)
					)
					(number "B23"
						(effects
							(font
								(size 1.27 1.27)
							)
						)
					)
				)
				(pin passive line
					(at 0 -58.42 0)
					(length 3.81)
					(name "B24"
						(effects
							(font
								(size 1.27 1.27)
							)
						)
					)
					(number "B24"
						(effects
							(font
								(size 1.27 1.27)
							)
						)
					)
				)
				(pin passive line
					(at 0 -60.96 0)
					(length 3.81)
					(name "B25"
						(effects
							(font
								(size 1.27 1.27)
							)
						)
					)
					(number "B25"
						(effects
							(font
								(size 1.27 1.27)
							)
						)
					)
				)
				(pin passive line
					(at 0 -63.5 0)
					(length 3.81)
					(name "B26"
						(effects
							(font
								(size 1.27 1.27)
							)
						)
					)
					(number "B26"
						(effects
							(font
								(size 1.27 1.27)
							)
						)
					)
				)
				(pin passive line
					(at 0 -66.04 0)
					(length 3.81)
					(name "B27"
						(effects
							(font
								(size 1.27 1.27)
							)
						)
					)
					(number "B27"
						(effects
							(font
								(size 1.27 1.27)
							)
						)
					)
				)
				(pin passive line
					(at 0 -68.58 0)
					(length 3.81)
					(name "B28"
						(effects
							(font
								(size 1.27 1.27)
							)
						)
					)
					(number "B28"
						(effects
							(font
								(size 1.27 1.27)
							)
						)
					)
				)
				(pin passive line
					(at 0 -71.12 0)
					(length 3.81)
					(name "B29"
						(effects
							(font
								(size 1.27 1.27)
							)
						)
					)
					(number "B29"
						(effects
							(font
								(size 1.27 1.27)
							)
						)
					)
				)
				(pin passive line
					(at 0 -73.66 0)
					(length 3.81)
					(name "B30"
						(effects
							(font
								(size 1.27 1.27)
							)
						)
					)
					(number "B30"
						(effects
							(font
								(size 1.27 1.27)
							)
						)
					)
				)
				(pin passive line
					(at 0 -76.2 0)
					(length 3.81)
					(name "B31"
						(effects
							(font
								(size 1.27 1.27)
							)
						)
					)
					(number "B31"
						(effects
							(font
								(size 1.27 1.27)
							)
						)
					)
				)
				(pin passive line
					(at 0 -78.74 0)
					(length 3.81)
					(name "B32"
						(effects
							(font
								(size 1.27 1.27)
							)
						)
					)
					(number "B32"
						(effects
							(font
								(size 1.27 1.27)
							)
						)
					)
				)
				(pin passive line
					(at 0 -81.28 0)
					(length 3.81)
					(name "B33"
						(effects
							(font
								(size 1.27 1.27)
							)
						)
					)
					(number "B33"
						(effects
							(font
								(size 1.27 1.27)
							)
						)
					)
				)
				(pin passive line
					(at 0 -83.82 0)
					(length 3.81)
					(name "B34"
						(effects
							(font
								(size 1.27 1.27)
							)
						)
					)
					(number "B34"
						(effects
							(font
								(size 1.27 1.27)
							)
						)
					)
				)
				(pin passive line
					(at 0 -86.36 0)
					(length 3.81)
					(name "B35"
						(effects
							(font
								(size 1.27 1.27)
							)
						)
					)
					(number "B35"
						(effects
							(font
								(size 1.27 1.27)
							)
						)
					)
				)
				(pin passive line
					(at 0 -88.9 0)
					(length 3.81)
					(name "B36"
						(effects
							(font
								(size 1.27 1.27)
							)
						)
					)
					(number "B36"
						(effects
							(font
								(size 1.27 1.27)
							)
						)
					)
				)
				(pin passive line
					(at 0 -91.44 0)
					(length 3.81)
					(name "B37"
						(effects
							(font
								(size 1.27 1.27)
							)
						)
					)
					(number "B37"
						(effects
							(font
								(size 1.27 1.27)
							)
						)
					)
				)
				(pin passive line
					(at 0 -93.98 0)
					(length 3.81)
					(name "B38"
						(effects
							(font
								(size 1.27 1.27)
							)
						)
					)
					(number "B38"
						(effects
							(font
								(size 1.27 1.27)
							)
						)
					)
				)
				(pin passive line
					(at 0 -96.52 0)
					(length 3.81)
					(name "B39"
						(effects
							(font
								(size 1.27 1.27)
							)
						)
					)
					(number "B39"
						(effects
							(font
								(size 1.27 1.27)
							)
						)
					)
				)
				(pin passive line
					(at 0 -99.06 0)
					(length 3.81)
					(name "B40"
						(effects
							(font
								(size 1.27 1.27)
							)
						)
					)
					(number "B40"
						(effects
							(font
								(size 1.27 1.27)
							)
						)
					)
				)
				(pin passive line
					(at 0 -101.6 0)
					(length 3.81)
					(name "B41"
						(effects
							(font
								(size 1.27 1.27)
							)
						)
					)
					(number "B41"
						(effects
							(font
								(size 1.27 1.27)
							)
						)
					)
				)
				(pin passive line
					(at 22.86 0 180)
					(length 3.81)
					(name "A1"
						(effects
							(font
								(size 1.27 1.27)
							)
						)
					)
					(number "A1"
						(effects
							(font
								(size 1.27 1.27)
							)
						)
					)
				)
				(pin passive line
					(at 22.86 -2.54 180)
					(length 3.81)
					(name "A2"
						(effects
							(font
								(size 1.27 1.27)
							)
						)
					)
					(number "A2"
						(effects
							(font
								(size 1.27 1.27)
							)
						)
					)
				)
				(pin passive line
					(at 22.86 -5.08 180)
					(length 3.81)
					(name "A3"
						(effects
							(font
								(size 1.27 1.27)
							)
						)
					)
					(number "A3"
						(effects
							(font
								(size 1.27 1.27)
							)
						)
					)
				)
				(pin passive line
					(at 22.86 -7.62 180)
					(length 3.81)
					(name "A4"
						(effects
							(font
								(size 1.27 1.27)
							)
						)
					)
					(number "A4"
						(effects
							(font
								(size 1.27 1.27)
							)
						)
					)
				)
				(pin passive line
					(at 22.86 -10.16 180)
					(length 3.81)
					(name "A5"
						(effects
							(font
								(size 1.27 1.27)
							)
						)
					)
					(number "A5"
						(effects
							(font
								(size 1.27 1.27)
							)
						)
					)
				)
				(pin passive line
					(at 22.86 -12.7 180)
					(length 3.81)
					(name "A6"
						(effects
							(font
								(size 1.27 1.27)
							)
						)
					)
					(number "A6"
						(effects
							(font
								(size 1.27 1.27)
							)
						)
					)
				)
				(pin passive line
					(at 22.86 -15.24 180)
					(length 3.81)
					(name "A7"
						(effects
							(font
								(size 1.27 1.27)
							)
						)
					)
					(number "A7"
						(effects
							(font
								(size 1.27 1.27)
							)
						)
					)
				)
				(pin passive line
					(at 22.86 -17.78 180)
					(length 3.81)
					(name "A8"
						(effects
							(font
								(size 1.27 1.27)
							)
						)
					)
					(number "A8"
						(effects
							(font
								(size 1.27 1.27)
							)
						)
					)
				)
				(pin passive line
					(at 22.86 -20.32 180)
					(length 3.81)
					(name "A9"
						(effects
							(font
								(size 1.27 1.27)
							)
						)
					)
					(number "A9"
						(effects
							(font
								(size 1.27 1.27)
							)
						)
					)
				)
				(pin passive line
					(at 22.86 -22.86 180)
					(length 3.81)
					(name "A10"
						(effects
							(font
								(size 1.27 1.27)
							)
						)
					)
					(number "A10"
						(effects
							(font
								(size 1.27 1.27)
							)
						)
					)
				)
				(pin passive line
					(at 22.86 -25.4 180)
					(length 3.81)
					(name "A11"
						(effects
							(font
								(size 1.27 1.27)
							)
						)
					)
					(number "A11"
						(effects
							(font
								(size 1.27 1.27)
							)
						)
					)
				)
				(pin passive line
					(at 22.86 -27.94 180)
					(length 3.81)
					(name "A12"
						(effects
							(font
								(size 1.27 1.27)
							)
						)
					)
					(number "A12"
						(effects
							(font
								(size 1.27 1.27)
							)
						)
					)
				)
				(pin passive line
					(at 22.86 -30.48 180)
					(length 3.81)
					(name "A13"
						(effects
							(font
								(size 1.27 1.27)
							)
						)
					)
					(number "A13"
						(effects
							(font
								(size 1.27 1.27)
							)
						)
					)
				)
				(pin passive line
					(at 22.86 -33.02 180)
					(length 3.81)
					(name "A14"
						(effects
							(font
								(size 1.27 1.27)
							)
						)
					)
					(number "A14"
						(effects
							(font
								(size 1.27 1.27)
							)
						)
					)
				)
				(pin passive line
					(at 22.86 -35.56 180)
					(length 3.81)
					(name "A15"
						(effects
							(font
								(size 1.27 1.27)
							)
						)
					)
					(number "A15"
						(effects
							(font
								(size 1.27 1.27)
							)
						)
					)
				)
				(pin passive line
					(at 22.86 -38.1 180)
					(length 3.81)
					(name "A16"
						(effects
							(font
								(size 1.27 1.27)
							)
						)
					)
					(number "A16"
						(effects
							(font
								(size 1.27 1.27)
							)
						)
					)
				)
				(pin passive line
					(at 22.86 -40.64 180)
					(length 3.81)
					(name "A17"
						(effects
							(font
								(size 1.27 1.27)
							)
						)
					)
					(number "A17"
						(effects
							(font
								(size 1.27 1.27)
							)
						)
					)
				)
				(pin passive line
					(at 22.86 -43.18 180)
					(length 3.81)
					(name "A18"
						(effects
							(font
								(size 1.27 1.27)
							)
						)
					)
					(number "A18"
						(effects
							(font
								(size 1.27 1.27)
							)
						)
					)
				)
				(pin passive line
					(at 22.86 -45.72 180)
					(length 3.81)
					(name "A19"
						(effects
							(font
								(size 1.27 1.27)
							)
						)
					)
					(number "A19"
						(effects
							(font
								(size 1.27 1.27)
							)
						)
					)
				)
				(pin passive line
					(at 22.86 -48.26 180)
					(length 3.81)
					(name "A20"
						(effects
							(font
								(size 1.27 1.27)
							)
						)
					)
					(number "A20"
						(effects
							(font
								(size 1.27 1.27)
							)
						)
					)
				)
				(pin passive line
					(at 22.86 -50.8 180)
					(length 3.81)
					(name "A21"
						(effects
							(font
								(size 1.27 1.27)
							)
						)
					)
					(number "A21"
						(effects
							(font
								(size 1.27 1.27)
							)
						)
					)
				)
				(pin passive line
					(at 22.86 -53.34 180)
					(length 3.81)
					(name "A22"
						(effects
							(font
								(size 1.27 1.27)
							)
						)
					)
					(number "A22"
						(effects
							(font
								(size 1.27 1.27)
							)
						)
					)
				)
				(pin passive line
					(at 22.86 -55.88 180)
					(length 3.81)
					(name "A23"
						(effects
							(font
								(size 1.27 1.27)
							)
						)
					)
					(number "A23"
						(effects
							(font
								(size 1.27 1.27)
							)
						)
					)
				)
				(pin passive line
					(at 22.86 -58.42 180)
					(length 3.81)
					(name "A24"
						(effects
							(font
								(size 1.27 1.27)
							)
						)
					)
					(number "A24"
						(effects
							(font
								(size 1.27 1.27)
							)
						)
					)
				)
				(pin passive line
					(at 22.86 -60.96 180)
					(length 3.81)
					(name "A25"
						(effects
							(font
								(size 1.27 1.27)
							)
						)
					)
					(number "A25"
						(effects
							(font
								(size 1.27 1.27)
							)
						)
					)
				)
				(pin passive line
					(at 22.86 -63.5 180)
					(length 3.81)
					(name "A26"
						(effects
							(font
								(size 1.27 1.27)
							)
						)
					)
					(number "A26"
						(effects
							(font
								(size 1.27 1.27)
							)
						)
					)
				)
				(pin passive line
					(at 22.86 -66.04 180)
					(length 3.81)
					(name "A27"
						(effects
							(font
								(size 1.27 1.27)
							)
						)
					)
					(number "A27"
						(effects
							(font
								(size 1.27 1.27)
							)
						)
					)
				)
				(pin passive line
					(at 22.86 -68.58 180)
					(length 3.81)
					(name "A28"
						(effects
							(font
								(size 1.27 1.27)
							)
						)
					)
					(number "A28"
						(effects
							(font
								(size 1.27 1.27)
							)
						)
					)
				)
				(pin passive line
					(at 22.86 -71.12 180)
					(length 3.81)
					(name "A29"
						(effects
							(font
								(size 1.27 1.27)
							)
						)
					)
					(number "A29"
						(effects
							(font
								(size 1.27 1.27)
							)
						)
					)
				)
				(pin passive line
					(at 22.86 -73.66 180)
					(length 3.81)
					(name "A30"
						(effects
							(font
								(size 1.27 1.27)
							)
						)
					)
					(number "A30"
						(effects
							(font
								(size 1.27 1.27)
							)
						)
					)
				)
				(pin passive line
					(at 22.86 -76.2 180)
					(length 3.81)
					(name "A31"
						(effects
							(font
								(size 1.27 1.27)
							)
						)
					)
					(number "A31"
						(effects
							(font
								(size 1.27 1.27)
							)
						)
					)
				)
				(pin passive line
					(at 22.86 -78.74 180)
					(length 3.81)
					(name "A32"
						(effects
							(font
								(size 1.27 1.27)
							)
						)
					)
					(number "A32"
						(effects
							(font
								(size 1.27 1.27)
							)
						)
					)
				)
				(pin passive line
					(at 22.86 -81.28 180)
					(length 3.81)
					(name "A33"
						(effects
							(font
								(size 1.27 1.27)
							)
						)
					)
					(number "A33"
						(effects
							(font
								(size 1.27 1.27)
							)
						)
					)
				)
				(pin passive line
					(at 22.86 -83.82 180)
					(length 3.81)
					(name "A34"
						(effects
							(font
								(size 1.27 1.27)
							)
						)
					)
					(number "A34"
						(effects
							(font
								(size 1.27 1.27)
							)
						)
					)
				)
				(pin passive line
					(at 22.86 -86.36 180)
					(length 3.81)
					(name "A35"
						(effects
							(font
								(size 1.27 1.27)
							)
						)
					)
					(number "A35"
						(effects
							(font
								(size 1.27 1.27)
							)
						)
					)
				)
				(pin passive line
					(at 22.86 -88.9 180)
					(length 3.81)
					(name "A36"
						(effects
							(font
								(size 1.27 1.27)
							)
						)
					)
					(number "A36"
						(effects
							(font
								(size 1.27 1.27)
							)
						)
					)
				)
				(pin passive line
					(at 22.86 -91.44 180)
					(length 3.81)
					(name "A37"
						(effects
							(font
								(size 1.27 1.27)
							)
						)
					)
					(number "A37"
						(effects
							(font
								(size 1.27 1.27)
							)
						)
					)
				)
				(pin passive line
					(at 22.86 -93.98 180)
					(length 3.81)
					(name "A38"
						(effects
							(font
								(size 1.27 1.27)
							)
						)
					)
					(number "A38"
						(effects
							(font
								(size 1.27 1.27)
							)
						)
					)
				)
				(pin passive line
					(at 22.86 -96.52 180)
					(length 3.81)
					(name "A39"
						(effects
							(font
								(size 1.27 1.27)
							)
						)
					)
					(number "A39"
						(effects
							(font
								(size 1.27 1.27)
							)
						)
					)
				)
				(pin passive line
					(at 22.86 -99.06 180)
					(length 3.81)
					(name "A40"
						(effects
							(font
								(size 1.27 1.27)
							)
						)
					)
					(number "A40"
						(effects
							(font
								(size 1.27 1.27)
							)
						)
					)
				)
				(pin passive line
					(at 22.86 -101.6 180)
					(length 3.81)
					(name "A41"
						(effects
							(font
								(size 1.27 1.27)
							)
						)
					)
					(number "A41"
						(effects
							(font
								(size 1.27 1.27)
							)
						)
					)
				)
			)
			(symbol "PCIe_x16_10146070-113Y0LF-vertical_2_1"
				(rectangle
					(start 3.81 2.54)
					(end 19.05 -109.22)
					(stroke
						(width 0.254)
						(type default)
					)
					(fill
						(type background)
					)
				)
				(pin passive line
					(at 0 0 0)
					(length 3.81)
					(name "B42"
						(effects
							(font
								(size 1.27 1.27)
							)
						)
					)
					(number "B42"
						(effects
							(font
								(size 1.27 1.27)
							)
						)
					)
				)
				(pin passive line
					(at 0 -2.54 0)
					(length 3.81)
					(name "B43"
						(effects
							(font
								(size 1.27 1.27)
							)
						)
					)
					(number "B43"
						(effects
							(font
								(size 1.27 1.27)
							)
						)
					)
				)
				(pin passive line
					(at 0 -5.08 0)
					(length 3.81)
					(name "B44"
						(effects
							(font
								(size 1.27 1.27)
							)
						)
					)
					(number "B44"
						(effects
							(font
								(size 1.27 1.27)
							)
						)
					)
				)
				(pin passive line
					(at 0 -7.62 0)
					(length 3.81)
					(name "B45"
						(effects
							(font
								(size 1.27 1.27)
							)
						)
					)
					(number "B45"
						(effects
							(font
								(size 1.27 1.27)
							)
						)
					)
				)
				(pin passive line
					(at 0 -10.16 0)
					(length 3.81)
					(name "B46"
						(effects
							(font
								(size 1.27 1.27)
							)
						)
					)
					(number "B46"
						(effects
							(font
								(size 1.27 1.27)
							)
						)
					)
				)
				(pin passive line
					(at 0 -12.7 0)
					(length 3.81)
					(name "B47"
						(effects
							(font
								(size 1.27 1.27)
							)
						)
					)
					(number "B47"
						(effects
							(font
								(size 1.27 1.27)
							)
						)
					)
				)
				(pin passive line
					(at 0 -15.24 0)
					(length 3.81)
					(name "B48"
						(effects
							(font
								(size 1.27 1.27)
							)
						)
					)
					(number "B48"
						(effects
							(font
								(size 1.27 1.27)
							)
						)
					)
				)
				(pin passive line
					(at 0 -17.78 0)
					(length 3.81)
					(name "B49"
						(effects
							(font
								(size 1.27 1.27)
							)
						)
					)
					(number "B49"
						(effects
							(font
								(size 1.27 1.27)
							)
						)
					)
				)
				(pin passive line
					(at 0 -20.32 0)
					(length 3.81)
					(name "B50"
						(effects
							(font
								(size 1.27 1.27)
							)
						)
					)
					(number "B50"
						(effects
							(font
								(size 1.27 1.27)
							)
						)
					)
				)
				(pin passive line
					(at 0 -22.86 0)
					(length 3.81)
					(name "B51"
						(effects
							(font
								(size 1.27 1.27)
							)
						)
					)
					(number "B51"
						(effects
							(font
								(size 1.27 1.27)
							)
						)
					)
				)
				(pin passive line
					(at 0 -25.4 0)
					(length 3.81)
					(name "B52"
						(effects
							(font
								(size 1.27 1.27)
							)
						)
					)
					(number "B52"
						(effects
							(font
								(size 1.27 1.27)
							)
						)
					)
				)
				(pin passive line
					(at 0 -27.94 0)
					(length 3.81)
					(name "B53"
						(effects
							(font
								(size 1.27 1.27)
							)
						)
					)
					(number "B53"
						(effects
							(font
								(size 1.27 1.27)
							)
						)
					)
				)
				(pin passive line
					(at 0 -30.48 0)
					(length 3.81)
					(name "B54"
						(effects
							(font
								(size 1.27 1.27)
							)
						)
					)
					(number "B54"
						(effects
							(font
								(size 1.27 1.27)
							)
						)
					)
				)
				(pin passive line
					(at 0 -33.02 0)
					(length 3.81)
					(name "B55"
						(effects
							(font
								(size 1.27 1.27)
							)
						)
					)
					(number "B55"
						(effects
							(font
								(size 1.27 1.27)
							)
						)
					)
				)
				(pin passive line
					(at 0 -35.56 0)
					(length 3.81)
					(name "B56"
						(effects
							(font
								(size 1.27 1.27)
							)
						)
					)
					(number "B56"
						(effects
							(font
								(size 1.27 1.27)
							)
						)
					)
				)
				(pin passive line
					(at 0 -38.1 0)
					(length 3.81)
					(name "B57"
						(effects
							(font
								(size 1.27 1.27)
							)
						)
					)
					(number "B57"
						(effects
							(font
								(size 1.27 1.27)
							)
						)
					)
				)
				(pin passive line
					(at 0 -40.64 0)
					(length 3.81)
					(name "B58"
						(effects
							(font
								(size 1.27 1.27)
							)
						)
					)
					(number "B58"
						(effects
							(font
								(size 1.27 1.27)
							)
						)
					)
				)
				(pin passive line
					(at 0 -43.18 0)
					(length 3.81)
					(name "B59"
						(effects
							(font
								(size 1.27 1.27)
							)
						)
					)
					(number "B59"
						(effects
							(font
								(size 1.27 1.27)
							)
						)
					)
				)
				(pin passive line
					(at 0 -45.72 0)
					(length 3.81)
					(name "B60"
						(effects
							(font
								(size 1.27 1.27)
							)
						)
					)
					(number "B60"
						(effects
							(font
								(size 1.27 1.27)
							)
						)
					)
				)
				(pin passive line
					(at 0 -48.26 0)
					(length 3.81)
					(name "B61"
						(effects
							(font
								(size 1.27 1.27)
							)
						)
					)
					(number "B61"
						(effects
							(font
								(size 1.27 1.27)
							)
						)
					)
				)
				(pin passive line
					(at 0 -50.8 0)
					(length 3.81)
					(name "B62"
						(effects
							(font
								(size 1.27 1.27)
							)
						)
					)
					(number "B62"
						(effects
							(font
								(size 1.27 1.27)
							)
						)
					)
				)
				(pin passive line
					(at 0 -53.34 0)
					(length 3.81)
					(name "B63"
						(effects
							(font
								(size 1.27 1.27)
							)
						)
					)
					(number "B63"
						(effects
							(font
								(size 1.27 1.27)
							)
						)
					)
				)
				(pin passive line
					(at 0 -55.88 0)
					(length 3.81)
					(name "B64"
						(effects
							(font
								(size 1.27 1.27)
							)
						)
					)
					(number "B64"
						(effects
							(font
								(size 1.27 1.27)
							)
						)
					)
				)
				(pin passive line
					(at 0 -58.42 0)
					(length 3.81)
					(name "B65"
						(effects
							(font
								(size 1.27 1.27)
							)
						)
					)
					(number "B65"
						(effects
							(font
								(size 1.27 1.27)
							)
						)
					)
				)
				(pin passive line
					(at 0 -60.96 0)
					(length 3.81)
					(name "B66"
						(effects
							(font
								(size 1.27 1.27)
							)
						)
					)
					(number "B66"
						(effects
							(font
								(size 1.27 1.27)
							)
						)
					)
				)
				(pin passive line
					(at 0 -63.5 0)
					(length 3.81)
					(name "B67"
						(effects
							(font
								(size 1.27 1.27)
							)
						)
					)
					(number "B67"
						(effects
							(font
								(size 1.27 1.27)
							)
						)
					)
				)
				(pin passive line
					(at 0 -66.04 0)
					(length 3.81)
					(name "B68"
						(effects
							(font
								(size 1.27 1.27)
							)
						)
					)
					(number "B68"
						(effects
							(font
								(size 1.27 1.27)
							)
						)
					)
				)
				(pin passive line
					(at 0 -68.58 0)
					(length 3.81)
					(name "B69"
						(effects
							(font
								(size 1.27 1.27)
							)
						)
					)
					(number "B69"
						(effects
							(font
								(size 1.27 1.27)
							)
						)
					)
				)
				(pin passive line
					(at 0 -71.12 0)
					(length 3.81)
					(name "B70"
						(effects
							(font
								(size 1.27 1.27)
							)
						)
					)
					(number "B70"
						(effects
							(font
								(size 1.27 1.27)
							)
						)
					)
				)
				(pin passive line
					(at 0 -73.66 0)
					(length 3.81)
					(name "B71"
						(effects
							(font
								(size 1.27 1.27)
							)
						)
					)
					(number "B71"
						(effects
							(font
								(size 1.27 1.27)
							)
						)
					)
				)
				(pin passive line
					(at 0 -76.2 0)
					(length 3.81)
					(name "B72"
						(effects
							(font
								(size 1.27 1.27)
							)
						)
					)
					(number "B72"
						(effects
							(font
								(size 1.27 1.27)
							)
						)
					)
				)
				(pin passive line
					(at 0 -78.74 0)
					(length 3.81)
					(name "B73"
						(effects
							(font
								(size 1.27 1.27)
							)
						)
					)
					(number "B73"
						(effects
							(font
								(size 1.27 1.27)
							)
						)
					)
				)
				(pin passive line
					(at 0 -81.28 0)
					(length 3.81)
					(name "B74"
						(effects
							(font
								(size 1.27 1.27)
							)
						)
					)
					(number "B74"
						(effects
							(font
								(size 1.27 1.27)
							)
						)
					)
				)
				(pin passive line
					(at 0 -83.82 0)
					(length 3.81)
					(name "B75"
						(effects
							(font
								(size 1.27 1.27)
							)
						)
					)
					(number "B75"
						(effects
							(font
								(size 1.27 1.27)
							)
						)
					)
				)
				(pin passive line
					(at 0 -86.36 0)
					(length 3.81)
					(name "B76"
						(effects
							(font
								(size 1.27 1.27)
							)
						)
					)
					(number "B76"
						(effects
							(font
								(size 1.27 1.27)
							)
						)
					)
				)
				(pin passive line
					(at 0 -88.9 0)
					(length 3.81)
					(name "B77"
						(effects
							(font
								(size 1.27 1.27)
							)
						)
					)
					(number "B77"
						(effects
							(font
								(size 1.27 1.27)
							)
						)
					)
				)
				(pin passive line
					(at 0 -91.44 0)
					(length 3.81)
					(name "B78"
						(effects
							(font
								(size 1.27 1.27)
							)
						)
					)
					(number "B78"
						(effects
							(font
								(size 1.27 1.27)
							)
						)
					)
				)
				(pin passive line
					(at 0 -93.98 0)
					(length 3.81)
					(name "B79"
						(effects
							(font
								(size 1.27 1.27)
							)
						)
					)
					(number "B79"
						(effects
							(font
								(size 1.27 1.27)
							)
						)
					)
				)
				(pin passive line
					(at 0 -96.52 0)
					(length 3.81)
					(name "B80"
						(effects
							(font
								(size 1.27 1.27)
							)
						)
					)
					(number "B80"
						(effects
							(font
								(size 1.27 1.27)
							)
						)
					)
				)
				(pin passive line
					(at 0 -99.06 0)
					(length 3.81)
					(name "B81"
						(effects
							(font
								(size 1.27 1.27)
							)
						)
					)
					(number "B81"
						(effects
							(font
								(size 1.27 1.27)
							)
						)
					)
				)
				(pin passive line
					(at 0 -101.6 0)
					(length 3.81)
					(name "B82"
						(effects
							(font
								(size 1.27 1.27)
							)
						)
					)
					(number "B82"
						(effects
							(font
								(size 1.27 1.27)
							)
						)
					)
				)
				(pin passive line
					(at 0 -106.68 0)
					(length 3.81)
					(name "S1"
						(effects
							(font
								(size 1.27 1.27)
							)
						)
					)
					(number "S1"
						(effects
							(font
								(size 1.27 1.27)
							)
						)
					)
				)
				(pin passive line
					(at 22.86 0 180)
					(length 3.81)
					(name "A42"
						(effects
							(font
								(size 1.27 1.27)
							)
						)
					)
					(number "A42"
						(effects
							(font
								(size 1.27 1.27)
							)
						)
					)
				)
				(pin passive line
					(at 22.86 -2.54 180)
					(length 3.81)
					(name "A43"
						(effects
							(font
								(size 1.27 1.27)
							)
						)
					)
					(number "A43"
						(effects
							(font
								(size 1.27 1.27)
							)
						)
					)
				)
				(pin passive line
					(at 22.86 -5.08 180)
					(length 3.81)
					(name "A44"
						(effects
							(font
								(size 1.27 1.27)
							)
						)
					)
					(number "A44"
						(effects
							(font
								(size 1.27 1.27)
							)
						)
					)
				)
				(pin passive line
					(at 22.86 -7.62 180)
					(length 3.81)
					(name "A45"
						(effects
							(font
								(size 1.27 1.27)
							)
						)
					)
					(number "A45"
						(effects
							(font
								(size 1.27 1.27)
							)
						)
					)
				)
				(pin passive line
					(at 22.86 -10.16 180)
					(length 3.81)
					(name "A46"
						(effects
							(font
								(size 1.27 1.27)
							)
						)
					)
					(number "A46"
						(effects
							(font
								(size 1.27 1.27)
							)
						)
					)
				)
				(pin passive line
					(at 22.86 -12.7 180)
					(length 3.81)
					(name "A47"
						(effects
							(font
								(size 1.27 1.27)
							)
						)
					)
					(number "A47"
						(effects
							(font
								(size 1.27 1.27)
							)
						)
					)
				)
				(pin passive line
					(at 22.86 -15.24 180)
					(length 3.81)
					(name "A48"
						(effects
							(font
								(size 1.27 1.27)
							)
						)
					)
					(number "A48"
						(effects
							(font
								(size 1.27 1.27)
							)
						)
					)
				)
				(pin passive line
					(at 22.86 -17.78 180)
					(length 3.81)
					(name "A49"
						(effects
							(font
								(size 1.27 1.27)
							)
						)
					)
					(number "A49"
						(effects
							(font
								(size 1.27 1.27)
							)
						)
					)
				)
				(pin passive line
					(at 22.86 -20.32 180)
					(length 3.81)
					(name "A50"
						(effects
							(font
								(size 1.27 1.27)
							)
						)
					)
					(number "A50"
						(effects
							(font
								(size 1.27 1.27)
							)
						)
					)
				)
				(pin passive line
					(at 22.86 -22.86 180)
					(length 3.81)
					(name "A51"
						(effects
							(font
								(size 1.27 1.27)
							)
						)
					)
					(number "A51"
						(effects
							(font
								(size 1.27 1.27)
							)
						)
					)
				)
				(pin passive line
					(at 22.86 -25.4 180)
					(length 3.81)
					(name "A52"
						(effects
							(font
								(size 1.27 1.27)
							)
						)
					)
					(number "A52"
						(effects
							(font
								(size 1.27 1.27)
							)
						)
					)
				)
				(pin passive line
					(at 22.86 -27.94 180)
					(length 3.81)
					(name "A53"
						(effects
							(font
								(size 1.27 1.27)
							)
						)
					)
					(number "A53"
						(effects
							(font
								(size 1.27 1.27)
							)
						)
					)
				)
				(pin passive line
					(at 22.86 -30.48 180)
					(length 3.81)
					(name "A54"
						(effects
							(font
								(size 1.27 1.27)
							)
						)
					)
					(number "A54"
						(effects
							(font
								(size 1.27 1.27)
							)
						)
					)
				)
				(pin passive line
					(at 22.86 -33.02 180)
					(length 3.81)
					(name "A55"
						(effects
							(font
								(size 1.27 1.27)
							)
						)
					)
					(number "A55"
						(effects
							(font
								(size 1.27 1.27)
							)
						)
					)
				)
				(pin passive line
					(at 22.86 -35.56 180)
					(length 3.81)
					(name "A56"
						(effects
							(font
								(size 1.27 1.27)
							)
						)
					)
					(number "A56"
						(effects
							(font
								(size 1.27 1.27)
							)
						)
					)
				)
				(pin passive line
					(at 22.86 -38.1 180)
					(length 3.81)
					(name "A57"
						(effects
							(font
								(size 1.27 1.27)
							)
						)
					)
					(number "A57"
						(effects
							(font
								(size 1.27 1.27)
							)
						)
					)
				)
				(pin passive line
					(at 22.86 -40.64 180)
					(length 3.81)
					(name "A58"
						(effects
							(font
								(size 1.27 1.27)
							)
						)
					)
					(number "A58"
						(effects
							(font
								(size 1.27 1.27)
							)
						)
					)
				)
				(pin passive line
					(at 22.86 -43.18 180)
					(length 3.81)
					(name "A59"
						(effects
							(font
								(size 1.27 1.27)
							)
						)
					)
					(number "A59"
						(effects
							(font
								(size 1.27 1.27)
							)
						)
					)
				)
				(pin passive line
					(at 22.86 -45.72 180)
					(length 3.81)
					(name "A60"
						(effects
							(font
								(size 1.27 1.27)
							)
						)
					)
					(number "A60"
						(effects
							(font
								(size 1.27 1.27)
							)
						)
					)
				)
				(pin passive line
					(at 22.86 -48.26 180)
					(length 3.81)
					(name "A61"
						(effects
							(font
								(size 1.27 1.27)
							)
						)
					)
					(number "A61"
						(effects
							(font
								(size 1.27 1.27)
							)
						)
					)
				)
				(pin passive line
					(at 22.86 -50.8 180)
					(length 3.81)
					(name "A62"
						(effects
							(font
								(size 1.27 1.27)
							)
						)
					)
					(number "A62"
						(effects
							(font
								(size 1.27 1.27)
							)
						)
					)
				)
				(pin passive line
					(at 22.86 -53.34 180)
					(length 3.81)
					(name "A63"
						(effects
							(font
								(size 1.27 1.27)
							)
						)
					)
					(number "A63"
						(effects
							(font
								(size 1.27 1.27)
							)
						)
					)
				)
				(pin passive line
					(at 22.86 -55.88 180)
					(length 3.81)
					(name "A64"
						(effects
							(font
								(size 1.27 1.27)
							)
						)
					)
					(number "A64"
						(effects
							(font
								(size 1.27 1.27)
							)
						)
					)
				)
				(pin passive line
					(at 22.86 -58.42 180)
					(length 3.81)
					(name "A65"
						(effects
							(font
								(size 1.27 1.27)
							)
						)
					)
					(number "A65"
						(effects
							(font
								(size 1.27 1.27)
							)
						)
					)
				)
				(pin passive line
					(at 22.86 -60.96 180)
					(length 3.81)
					(name "A66"
						(effects
							(font
								(size 1.27 1.27)
							)
						)
					)
					(number "A66"
						(effects
							(font
								(size 1.27 1.27)
							)
						)
					)
				)
				(pin passive line
					(at 22.86 -63.5 180)
					(length 3.81)
					(name "A67"
						(effects
							(font
								(size 1.27 1.27)
							)
						)
					)
					(number "A67"
						(effects
							(font
								(size 1.27 1.27)
							)
						)
					)
				)
				(pin passive line
					(at 22.86 -66.04 180)
					(length 3.81)
					(name "A68"
						(effects
							(font
								(size 1.27 1.27)
							)
						)
					)
					(number "A68"
						(effects
							(font
								(size 1.27 1.27)
							)
						)
					)
				)
				(pin passive line
					(at 22.86 -68.58 180)
					(length 3.81)
					(name "A69"
						(effects
							(font
								(size 1.27 1.27)
							)
						)
					)
					(number "A69"
						(effects
							(font
								(size 1.27 1.27)
							)
						)
					)
				)
				(pin passive line
					(at 22.86 -71.12 180)
					(length 3.81)
					(name "A70"
						(effects
							(font
								(size 1.27 1.27)
							)
						)
					)
					(number "A70"
						(effects
							(font
								(size 1.27 1.27)
							)
						)
					)
				)
				(pin passive line
					(at 22.86 -73.66 180)
					(length 3.81)
					(name "A71"
						(effects
							(font
								(size 1.27 1.27)
							)
						)
					)
					(number "A71"
						(effects
							(font
								(size 1.27 1.27)
							)
						)
					)
				)
				(pin passive line
					(at 22.86 -76.2 180)
					(length 3.81)
					(name "A72"
						(effects
							(font
								(size 1.27 1.27)
							)
						)
					)
					(number "A72"
						(effects
							(font
								(size 1.27 1.27)
							)
						)
					)
				)
				(pin passive line
					(at 22.86 -78.74 180)
					(length 3.81)
					(name "A73"
						(effects
							(font
								(size 1.27 1.27)
							)
						)
					)
					(number "A73"
						(effects
							(font
								(size 1.27 1.27)
							)
						)
					)
				)
				(pin passive line
					(at 22.86 -81.28 180)
					(length 3.81)
					(name "A74"
						(effects
							(font
								(size 1.27 1.27)
							)
						)
					)
					(number "A74"
						(effects
							(font
								(size 1.27 1.27)
							)
						)
					)
				)
				(pin passive line
					(at 22.86 -83.82 180)
					(length 3.81)
					(name "A75"
						(effects
							(font
								(size 1.27 1.27)
							)
						)
					)
					(number "A75"
						(effects
							(font
								(size 1.27 1.27)
							)
						)
					)
				)
				(pin passive line
					(at 22.86 -86.36 180)
					(length 3.81)
					(name "A76"
						(effects
							(font
								(size 1.27 1.27)
							)
						)
					)
					(number "A76"
						(effects
							(font
								(size 1.27 1.27)
							)
						)
					)
				)
				(pin passive line
					(at 22.86 -88.9 180)
					(length 3.81)
					(name "A77"
						(effects
							(font
								(size 1.27 1.27)
							)
						)
					)
					(number "A77"
						(effects
							(font
								(size 1.27 1.27)
							)
						)
					)
				)
				(pin passive line
					(at 22.86 -91.44 180)
					(length 3.81)
					(name "A78"
						(effects
							(font
								(size 1.27 1.27)
							)
						)
					)
					(number "A78"
						(effects
							(font
								(size 1.27 1.27)
							)
						)
					)
				)
				(pin passive line
					(at 22.86 -93.98 180)
					(length 3.81)
					(name "A79"
						(effects
							(font
								(size 1.27 1.27)
							)
						)
					)
					(number "A79"
						(effects
							(font
								(size 1.27 1.27)
							)
						)
					)
				)
				(pin passive line
					(at 22.86 -96.52 180)
					(length 3.81)
					(name "A80"
						(effects
							(font
								(size 1.27 1.27)
							)
						)
					)
					(number "A80"
						(effects
							(font
								(size 1.27 1.27)
							)
						)
					)
				)
				(pin passive line
					(at 22.86 -99.06 180)
					(length 3.81)
					(name "A81"
						(effects
							(font
								(size 1.27 1.27)
							)
						)
					)
					(number "A81"
						(effects
							(font
								(size 1.27 1.27)
							)
						)
					)
				)
				(pin passive line
					(at 22.86 -101.6 180)
					(length 3.81)
					(name "A82"
						(effects
							(font
								(size 1.27 1.27)
							)
						)
					)
					(number "A82"
						(effects
							(font
								(size 1.27 1.27)
							)
						)
					)
				)
				(pin passive line
					(at 22.86 -106.68 180)
					(length 3.81)
					(name "S2"
						(effects
							(font
								(size 1.27 1.27)
							)
						)
					)
					(number "S2"
						(effects
							(font
								(size 1.27 1.27)
							)
						)
					)
				)
			)
		)
	(symbol "antmicroResistors0402:R_0R_0402"
			(pin_numbers
				(hide yes)
			)
			(pin_names
				(hide yes)
			)
			(exclude_from_sim no)
			(in_bom yes)
			(on_board yes)
			(property "Reference" "R"
				(at 20.32 -5.08 0)
				(effects
					(font
						(size 1.27 1.27)
						(thickness 0.15)
					)
					(justify left bottom)
				)
			)
			(property "Value" "R_0R_0402"
				(at 20.32 -12.7 0)
				(effects
					(font
						(size 1.27 1.27)
						(thickness 0.15)
					)
					(justify left bottom)
					(hide yes)
				)
			)
			(property "Footprint" "antmicro-footprints:R_0402_1005Metric"
				(at 20.32 -15.24 0)
				(effects
					(font
						(size 1.27 1.27)
						(thickness 0.15)
					)
					(justify left bottom)
					(hide yes)
				)
			)
			(property "Datasheet" "https://industrial.panasonic.com/cdbs/www-data/pdf/RDA0000/AOA0000C301.pdf"
				(at 20.32 -17.78 0)
				(effects
					(font
						(size 1.27 1.27)
						(thickness 0.15)
					)
					(justify left bottom)
					(hide yes)
				)
			)
			(property "Description" "SMD Chip Resistor, Jumper, 0 ohm, 100 mW, 0402 [1005 Metric], Thick Film, General Purpose"
				(at 0 0 0)
				(effects
					(font
						(size 1.27 1.27)
					)
					(hide yes)
				)
			)
			(property "MPN" "ERJ2GE0R00X"
				(at 20.32 -20.32 0)
				(effects
					(font
						(size 1.27 1.27)
						(thickness 0.15)
					)
					(justify left bottom)
					(hide yes)
				)
			)
			(property "Manufacturer" "Panasonic"
				(at 20.32 -22.86 0)
				(effects
					(font
						(size 1.27 1.27)
						(thickness 0.15)
					)
					(justify left bottom)
					(hide yes)
				)
			)
			(property "License" "Apache-2.0"
				(at 20.32 -25.4 0)
				(effects
					(font
						(size 1.27 1.27)
						(thickness 0.15)
					)
					(justify left bottom)
					(hide yes)
				)
			)
			(property "Author" "Antmicro"
				(at 20.32 -27.94 0)
				(effects
					(font
						(size 1.27 1.27)
						(thickness 0.15)
					)
					(justify left bottom)
					(hide yes)
				)
			)
			(property "Val" "0R"
				(at 20.32 -7.62 0)
				(effects
					(font
						(size 1.27 1.27)
						(thickness 0.15)
					)
					(justify left bottom)
				)
			)
			(property "Tolerance" "~"
				(at 20.32 -10.16 0)
				(effects
					(font
						(size 1.27 1.27)
					)
					(justify left bottom)
					(hide yes)
				)
			)
			(property "Current" "1A"
				(at 20.32 -30.48 0)
				(effects
					(font
						(size 1.27 1.27)
						(thickness 0.15)
					)
					(justify left bottom)
					(hide yes)
				)
			)
			(property "ki_keywords" "0402, SMT, RESISTOR, PASSIVE"
				(at 0 0 0)
				(effects
					(font
						(size 1.27 1.27)
					)
					(hide yes)
				)
			)
			(symbol "R_0R_0402_0_1"
				(rectangle
					(start 0.635 0.889)
					(end 4.445 -0.889)
					(stroke
						(width 0.254)
						(type default)
					)
					(fill
						(type none)
					)
				)
			)
			(symbol "R_0R_0402_1_1"
				(pin passive line
					(at 0 0 0)
					(length 0.635)
					(name "~"
						(effects
							(font
								(size 1.27 1.27)
							)
						)
					)
					(number "1"
						(effects
							(font
								(size 1.27 1.27)
							)
						)
					)
				)
				(pin passive line
					(at 5.08 0 180)
					(length 0.635)
					(name "~"
						(effects
							(font
								(size 1.27 1.27)
							)
						)
					)
					(number "2"
						(effects
							(font
								(size 1.27 1.27)
							)
						)
					)
				)
			)
		)
	(symbol "antmicroResistors0402:R_100k_0402"
			(pin_numbers
				(hide yes)
			)
			(pin_names
				(hide yes)
			)
			(exclude_from_sim no)
			(in_bom yes)
			(on_board yes)
			(property "Reference" "R"
				(at 20.32 -5.08 0)
				(effects
					(font
						(size 1.27 1.27)
						(thickness 0.15)
					)
					(justify left bottom)
				)
			)
			(property "Value" "R_100k_0402"
				(at 20.32 -12.7 0)
				(effects
					(font
						(size 1.27 1.27)
						(thickness 0.15)
					)
					(justify left bottom)
					(hide yes)
				)
			)
			(property "Footprint" "antmicro-footprints:R_0402_1005Metric"
				(at 20.32 -15.24 0)
				(effects
					(font
						(size 1.27 1.27)
						(thickness 0.15)
					)
					(justify left bottom)
					(hide yes)
				)
			)
			(property "Datasheet" "https://www.bourns.com/docs/product-datasheets/cr.pdf"
				(at 20.32 -17.78 0)
				(effects
					(font
						(size 1.27 1.27)
						(thickness 0.15)
					)
					(justify left bottom)
					(hide yes)
				)
			)
			(property "Description" "SMD Chip Resistor, 100 kohm, ± 1%, 62.5 mW, 0402 [1005 Metric], Thick Film, General Purpose"
				(at 0 0 0)
				(effects
					(font
						(size 1.27 1.27)
					)
					(hide yes)
				)
			)
			(property "MPN" "CR0402-FX-1003GLF"
				(at 20.32 -20.32 0)
				(effects
					(font
						(size 1.27 1.27)
						(thickness 0.15)
					)
					(justify left bottom)
					(hide yes)
				)
			)
			(property "Manufacturer" "Bourns"
				(at 20.32 -22.86 0)
				(effects
					(font
						(size 1.27 1.27)
						(thickness 0.15)
					)
					(justify left bottom)
					(hide yes)
				)
			)
			(property "License" "Apache-2.0"
				(at 20.32 -25.4 0)
				(effects
					(font
						(size 1.27 1.27)
						(thickness 0.15)
					)
					(justify left bottom)
					(hide yes)
				)
			)
			(property "Author" "Antmicro"
				(at 20.32 -27.94 0)
				(effects
					(font
						(size 1.27 1.27)
						(thickness 0.15)
					)
					(justify left bottom)
					(hide yes)
				)
			)
			(property "Val" "100k"
				(at 20.32 -7.62 0)
				(effects
					(font
						(size 1.27 1.27)
						(thickness 0.15)
					)
					(justify left bottom)
				)
			)
			(property "Tolerance" "1%"
				(at 20.32 -10.16 0)
				(effects
					(font
						(size 1.27 1.27)
					)
					(justify left bottom)
					(hide yes)
				)
			)
			(property "ki_keywords" "0402, SMT, RESISTOR, PASSIVE"
				(at 0 0 0)
				(effects
					(font
						(size 1.27 1.27)
					)
					(hide yes)
				)
			)
			(symbol "R_100k_0402_0_1"
				(rectangle
					(start 0.635 0.889)
					(end 4.445 -0.889)
					(stroke
						(width 0.254)
						(type default)
					)
					(fill
						(type none)
					)
				)
			)
			(symbol "R_100k_0402_1_1"
				(pin passive line
					(at 0 0 0)
					(length 0.635)
					(name "~"
						(effects
							(font
								(size 1.27 1.27)
							)
						)
					)
					(number "1"
						(effects
							(font
								(size 1.27 1.27)
							)
						)
					)
				)
				(pin passive line
					(at 5.08 0 180)
					(length 0.635)
					(name "~"
						(effects
							(font
								(size 1.27 1.27)
							)
						)
					)
					(number "2"
						(effects
							(font
								(size 1.27 1.27)
							)
						)
					)
				)
			)
		)
	(symbol "antmicroResistors0402:R_10k_0.1%_0402"
			(pin_numbers
				(hide yes)
			)
			(pin_names
				(hide yes)
			)
			(exclude_from_sim no)
			(in_bom yes)
			(on_board yes)
			(property "Reference" "R"
				(at 15.24 -5.08 0)
				(effects
					(font
						(size 1.27 1.27)
						(thickness 0.15)
					)
					(justify left bottom)
				)
			)
			(property "Value" "R_10k_0.1%_0402"
				(at 15.24 -12.7 0)
				(effects
					(font
						(size 1.27 1.27)
						(thickness 0.15)
					)
					(justify left bottom)
					(hide yes)
				)
			)
			(property "Footprint" "antmicro-footprints:R_0402_1005Metric"
				(at 15.24 -15.24 0)
				(effects
					(font
						(size 1.27 1.27)
						(thickness 0.15)
					)
					(justify left bottom)
					(hide yes)
				)
			)
			(property "Datasheet" "https://www.mouser.com/datasheet/2/54/CRT-1649066.pdf"
				(at 15.24 -17.78 0)
				(effects
					(font
						(size 1.27 1.27)
						(thickness 0.15)
					)
					(justify left bottom)
					(hide yes)
				)
			)
			(property "Description" "SMD Chip Resistor, 10 kohm, ± 0.1%, 62.5 mW, 0402 [1005 Metric], Thin Film, Precision Resistors"
				(at 0 0 0)
				(effects
					(font
						(size 1.27 1.27)
					)
					(hide yes)
				)
			)
			(property "MPN" "CRT0402-BY-1002GLF "
				(at 15.24 -20.32 0)
				(effects
					(font
						(size 1.27 1.27)
						(thickness 0.15)
					)
					(justify left bottom)
					(hide yes)
				)
			)
			(property "Val" "10k"
				(at 15.24 -7.62 0)
				(effects
					(font
						(size 1.27 1.27)
						(thickness 0.15)
					)
					(justify left bottom)
				)
			)
			(property "Tolerance" "0.1%"
				(at 15.24 -10.16 0)
				(effects
					(font
						(size 1.27 1.27)
						(thickness 0.15)
					)
					(justify left bottom)
					(hide yes)
				)
			)
			(property "Author" "Antmicro"
				(at 15.24 -22.86 0)
				(effects
					(font
						(size 1.27 1.27)
						(thickness 0.15)
					)
					(justify left bottom)
					(hide yes)
				)
			)
			(property "License" "Apache-2.0"
				(at 15.24 -25.4 0)
				(effects
					(font
						(size 1.27 1.27)
						(thickness 0.15)
					)
					(justify left bottom)
					(hide yes)
				)
			)
			(property "Manufacturer" "Bourns"
				(at 15.24 -27.94 0)
				(effects
					(font
						(size 1.27 1.27)
						(thickness 0.15)
					)
					(justify left bottom)
					(hide yes)
				)
			)
			(property "ki_keywords" "0402, SMT, RESISTOR, PASSIVE"
				(at 0 0 0)
				(effects
					(font
						(size 1.27 1.27)
					)
					(hide yes)
				)
			)
			(symbol "R_10k_0.1%_0402_0_1"
				(rectangle
					(start 0.635 0.889)
					(end 4.445 -0.889)
					(stroke
						(width 0.254)
						(type default)
					)
					(fill
						(type none)
					)
				)
			)
			(symbol "R_10k_0.1%_0402_1_1"
				(pin passive line
					(at 0 0 0)
					(length 0.635)
					(name "~"
						(effects
							(font
								(size 1.27 1.27)
							)
						)
					)
					(number "1"
						(effects
							(font
								(size 1.27 1.27)
							)
						)
					)
				)
				(pin passive line
					(at 5.08 0 180)
					(length 0.635)
					(name "~"
						(effects
							(font
								(size 1.27 1.27)
							)
						)
					)
					(number "2"
						(effects
							(font
								(size 1.27 1.27)
							)
						)
					)
				)
			)
		)
	(symbol "antmicroResistors0402:R_10k_0402"
			(pin_numbers
				(hide yes)
			)
			(pin_names
				(hide yes)
			)
			(exclude_from_sim no)
			(in_bom yes)
			(on_board yes)
			(property "Reference" "R"
				(at 20.32 -5.08 0)
				(effects
					(font
						(size 1.27 1.27)
						(thickness 0.15)
					)
					(justify left bottom)
				)
			)
			(property "Value" "R_10k_0402"
				(at 20.32 -12.7 0)
				(effects
					(font
						(size 1.27 1.27)
						(thickness 0.15)
					)
					(justify left bottom)
					(hide yes)
				)
			)
			(property "Footprint" "antmicro-footprints:R_0402_1005Metric"
				(at 20.32 -15.24 0)
				(effects
					(font
						(size 1.27 1.27)
						(thickness 0.15)
					)
					(justify left bottom)
					(hide yes)
				)
			)
			(property "Datasheet" "https://www.bourns.com/docs/product-datasheets/cr.pdf"
				(at 20.32 -17.78 0)
				(effects
					(font
						(size 1.27 1.27)
						(thickness 0.15)
					)
					(justify left bottom)
					(hide yes)
				)
			)
			(property "Description" "SMD Chip Resistor, 10 kohm, ± 1%, 62.5 mW, 0402 [1005 Metric], Thick Film, General Purpose"
				(at 0 0 0)
				(effects
					(font
						(size 1.27 1.27)
					)
					(hide yes)
				)
			)
			(property "MPN" "CR0402-FX-1002GLF"
				(at 20.32 -20.32 0)
				(effects
					(font
						(size 1.27 1.27)
						(thickness 0.15)
					)
					(justify left bottom)
					(hide yes)
				)
			)
			(property "Manufacturer" "Bourns"
				(at 20.32 -22.86 0)
				(effects
					(font
						(size 1.27 1.27)
						(thickness 0.15)
					)
					(justify left bottom)
					(hide yes)
				)
			)
			(property "License" "Apache-2.0"
				(at 20.32 -25.4 0)
				(effects
					(font
						(size 1.27 1.27)
						(thickness 0.15)
					)
					(justify left bottom)
					(hide yes)
				)
			)
			(property "Author" "Antmicro"
				(at 20.32 -27.94 0)
				(effects
					(font
						(size 1.27 1.27)
						(thickness 0.15)
					)
					(justify left bottom)
					(hide yes)
				)
			)
			(property "Val" "10k"
				(at 20.32 -7.62 0)
				(effects
					(font
						(size 1.27 1.27)
						(thickness 0.15)
					)
					(justify left bottom)
				)
			)
			(property "Tolerance" "1%"
				(at 20.32 -10.16 0)
				(effects
					(font
						(size 1.27 1.27)
					)
					(justify left bottom)
					(hide yes)
				)
			)
			(property "ki_keywords" "0402, SMT, RESISTOR, PASSIVE"
				(at 0 0 0)
				(effects
					(font
						(size 1.27 1.27)
					)
					(hide yes)
				)
			)
			(symbol "R_10k_0402_0_1"
				(rectangle
					(start 0.635 0.889)
					(end 4.445 -0.889)
					(stroke
						(width 0.254)
						(type default)
					)
					(fill
						(type none)
					)
				)
			)
			(symbol "R_10k_0402_1_1"
				(pin passive line
					(at 0 0 0)
					(length 0.635)
					(name "~"
						(effects
							(font
								(size 1.27 1.27)
							)
						)
					)
					(number "1"
						(effects
							(font
								(size 1.27 1.27)
							)
						)
					)
				)
				(pin passive line
					(at 5.08 0 180)
					(length 0.635)
					(name "~"
						(effects
							(font
								(size 1.27 1.27)
							)
						)
					)
					(number "2"
						(effects
							(font
								(size 1.27 1.27)
							)
						)
					)
				)
			)
		)
	(symbol "antmicroResistors0402:R_140k_0.1%_0402"
			(pin_numbers
				(hide yes)
			)
			(pin_names
				(hide yes)
			)
			(exclude_from_sim no)
			(in_bom yes)
			(on_board yes)
			(property "Reference" "R"
				(at 15.24 -5.08 0)
				(effects
					(font
						(size 1.27 1.27)
						(thickness 0.15)
					)
					(justify left bottom)
				)
			)
			(property "Value" "R_140k_0.1%_0402"
				(at 15.24 -10.16 0)
				(effects
					(font
						(size 1.27 1.27)
						(thickness 0.15)
					)
					(justify left bottom)
					(hide yes)
				)
			)
			(property "Footprint" "antmicro-footprints:R_0402_1005Metric"
				(at 15.24 -12.7 0)
				(effects
					(font
						(size 1.27 1.27)
						(thickness 0.15)
					)
					(justify left bottom)
					(hide yes)
				)
			)
			(property "Datasheet" "https://www.vishay.com/docs/28758/tnpw_e3.pdf"
				(at 15.24 -15.24 0)
				(effects
					(font
						(size 1.27 1.27)
						(thickness 0.15)
					)
					(justify left bottom)
					(hide yes)
				)
			)
			(property "Description" "SMD Chip Resistor, Ceramic, 140 kohm, ± 0.1%, 62.5 mW, 0402 [1005 Metric], Thin Film, Precision resistors"
				(at 0 0 0)
				(effects
					(font
						(size 1.27 1.27)
					)
					(hide yes)
				)
			)
			(property "MPN" "RT0402BRD07140KL"
				(at 15.24 -17.78 0)
				(effects
					(font
						(size 1.27 1.27)
						(thickness 0.15)
					)
					(justify left bottom)
					(hide yes)
				)
			)
			(property "Val" "140k"
				(at 15.24 -7.62 0)
				(effects
					(font
						(size 1.27 1.27)
						(thickness 0.15)
					)
					(justify left bottom)
				)
			)
			(property "Tolerance" "0.1%"
				(at 15.24 -20.32 0)
				(effects
					(font
						(size 1.27 1.27)
						(thickness 0.15)
					)
					(justify left bottom)
					(hide yes)
				)
			)
			(property "Author" "Antmicro"
				(at 15.24 -22.86 0)
				(effects
					(font
						(size 1.27 1.27)
						(thickness 0.15)
					)
					(justify left bottom)
					(hide yes)
				)
			)
			(property "License" "Apache-2.0"
				(at 15.24 -25.4 0)
				(effects
					(font
						(size 1.27 1.27)
						(thickness 0.15)
					)
					(justify left bottom)
					(hide yes)
				)
			)
			(property "Manufacturer" "YAGEO"
				(at 15.24 -27.94 0)
				(effects
					(font
						(size 1.27 1.27)
						(thickness 0.15)
					)
					(justify left bottom)
					(hide yes)
				)
			)
			(property "ki_keywords" "0402, SMT, RESISTOR, PASSIVE"
				(at 0 0 0)
				(effects
					(font
						(size 1.27 1.27)
					)
					(hide yes)
				)
			)
			(symbol "R_140k_0.1%_0402_0_1"
				(rectangle
					(start 0.635 0.889)
					(end 4.445 -0.889)
					(stroke
						(width 0.254)
						(type default)
					)
					(fill
						(type none)
					)
				)
			)
			(symbol "R_140k_0.1%_0402_1_1"
				(pin passive line
					(at 0 0 0)
					(length 0.635)
					(name "~"
						(effects
							(font
								(size 1.27 1.27)
							)
						)
					)
					(number "1"
						(effects
							(font
								(size 1.27 1.27)
							)
						)
					)
				)
				(pin passive line
					(at 5.08 0 180)
					(length 0.635)
					(name "~"
						(effects
							(font
								(size 1.27 1.27)
							)
						)
					)
					(number "2"
						(effects
							(font
								(size 1.27 1.27)
							)
						)
					)
				)
			)
		)
	(symbol "antmicroResistors0402:R_158k_0402"
			(pin_numbers
				(hide yes)
			)
			(pin_names
				(hide yes)
			)
			(exclude_from_sim no)
			(in_bom yes)
			(on_board yes)
			(property "Reference" "R"
				(at 20.32 -5.08 0)
				(effects
					(font
						(size 1.27 1.27)
						(thickness 0.15)
					)
					(justify left bottom)
				)
			)
			(property "Value" "R_158k_0402"
				(at 20.32 -12.7 0)
				(effects
					(font
						(size 1.27 1.27)
						(thickness 0.15)
					)
					(justify left bottom)
					(hide yes)
				)
			)
			(property "Footprint" "antmicro-footprints:R_0402_1005Metric"
				(at 20.32 -15.24 0)
				(effects
					(font
						(size 1.27 1.27)
						(thickness 0.15)
					)
					(justify left bottom)
					(hide yes)
				)
			)
			(property "Datasheet" "https://www.bourns.com/docs/product-datasheets/cr.pdf"
				(at 20.32 -17.78 0)
				(effects
					(font
						(size 1.27 1.27)
						(thickness 0.15)
					)
					(justify left bottom)
					(hide yes)
				)
			)
			(property "Description" "SMD Chip Resistor, 158 kohm, ± 1%, 100 mW, 0402 [1005 Metric], Thick Film, Precision"
				(at 0 0 0)
				(effects
					(font
						(size 1.27 1.27)
					)
					(hide yes)
				)
			)
			(property "MPN" "CR0402-FX-1583GLF"
				(at 20.32 -20.32 0)
				(effects
					(font
						(size 1.27 1.27)
						(thickness 0.15)
					)
					(justify left bottom)
					(hide yes)
				)
			)
			(property "Manufacturer" "Bourns"
				(at 20.32 -22.86 0)
				(effects
					(font
						(size 1.27 1.27)
						(thickness 0.15)
					)
					(justify left bottom)
					(hide yes)
				)
			)
			(property "License" "Apache-2.0"
				(at 20.32 -25.4 0)
				(effects
					(font
						(size 1.27 1.27)
						(thickness 0.15)
					)
					(justify left bottom)
					(hide yes)
				)
			)
			(property "Author" "Antmicro"
				(at 20.32 -27.94 0)
				(effects
					(font
						(size 1.27 1.27)
						(thickness 0.15)
					)
					(justify left bottom)
					(hide yes)
				)
			)
			(property "Val" "158k"
				(at 20.32 -7.62 0)
				(effects
					(font
						(size 1.27 1.27)
						(thickness 0.15)
					)
					(justify left bottom)
				)
			)
			(property "Tolerance" "1%"
				(at 20.32 -10.16 0)
				(effects
					(font
						(size 1.27 1.27)
					)
					(justify left bottom)
					(hide yes)
				)
			)
			(property "ki_keywords" "0402, SMT, RESISTOR, PASSIVE"
				(at 0 0 0)
				(effects
					(font
						(size 1.27 1.27)
					)
					(hide yes)
				)
			)
			(symbol "R_158k_0402_0_1"
				(rectangle
					(start 0.635 0.889)
					(end 4.445 -0.889)
					(stroke
						(width 0.254)
						(type default)
					)
					(fill
						(type none)
					)
				)
			)
			(symbol "R_158k_0402_1_1"
				(pin passive line
					(at 0 0 0)
					(length 0.635)
					(name "~"
						(effects
							(font
								(size 1.27 1.27)
							)
						)
					)
					(number "1"
						(effects
							(font
								(size 1.27 1.27)
							)
						)
					)
				)
				(pin passive line
					(at 5.08 0 180)
					(length 0.635)
					(name "~"
						(effects
							(font
								(size 1.27 1.27)
							)
						)
					)
					(number "2"
						(effects
							(font
								(size 1.27 1.27)
							)
						)
					)
				)
			)
		)
	(symbol "antmicroResistors0402:R_15k_0402"
			(pin_numbers
				(hide yes)
			)
			(pin_names
				(hide yes)
			)
			(exclude_from_sim no)
			(in_bom yes)
			(on_board yes)
			(property "Reference" "R"
				(at 20.32 -5.08 0)
				(effects
					(font
						(size 1.27 1.27)
						(thickness 0.15)
					)
					(justify left bottom)
				)
			)
			(property "Value" "R_15k_0402"
				(at 20.32 -12.7 0)
				(effects
					(font
						(size 1.27 1.27)
						(thickness 0.15)
					)
					(justify left bottom)
					(hide yes)
				)
			)
			(property "Footprint" "antmicro-footprints:R_0402_1005Metric"
				(at 20.32 -15.24 0)
				(effects
					(font
						(size 1.27 1.27)
						(thickness 0.15)
					)
					(justify left bottom)
					(hide yes)
				)
			)
			(property "Datasheet" "https://www.bourns.com/docs/product-datasheets/cr.pdf"
				(at 20.32 -17.78 0)
				(effects
					(font
						(size 1.27 1.27)
						(thickness 0.15)
					)
					(justify left bottom)
					(hide yes)
				)
			)
			(property "Description" "SMD Chip Resistor, 15 kohm, ± 1%, 62.5 mW, 0402 [1005 Metric], Thick Film, General Purpose"
				(at 0 0 0)
				(effects
					(font
						(size 1.27 1.27)
					)
					(hide yes)
				)
			)
			(property "MPN" "CR0402-FX-1502GLF"
				(at 20.32 -20.32 0)
				(effects
					(font
						(size 1.27 1.27)
						(thickness 0.15)
					)
					(justify left bottom)
					(hide yes)
				)
			)
			(property "Manufacturer" "Bourns"
				(at 20.32 -22.86 0)
				(effects
					(font
						(size 1.27 1.27)
						(thickness 0.15)
					)
					(justify left bottom)
					(hide yes)
				)
			)
			(property "License" "Apache-2.0"
				(at 20.32 -25.4 0)
				(effects
					(font
						(size 1.27 1.27)
						(thickness 0.15)
					)
					(justify left bottom)
					(hide yes)
				)
			)
			(property "Author" "Antmicro"
				(at 20.32 -27.94 0)
				(effects
					(font
						(size 1.27 1.27)
						(thickness 0.15)
					)
					(justify left bottom)
					(hide yes)
				)
			)
			(property "Val" "15k"
				(at 20.32 -7.62 0)
				(effects
					(font
						(size 1.27 1.27)
						(thickness 0.15)
					)
					(justify left bottom)
				)
			)
			(property "Tolerance" "1%"
				(at 20.32 -10.16 0)
				(effects
					(font
						(size 1.27 1.27)
					)
					(justify left bottom)
					(hide yes)
				)
			)
			(property "ki_keywords" "0402, SMT, RESISTOR, PASSIVE"
				(at 0 0 0)
				(effects
					(font
						(size 1.27 1.27)
					)
					(hide yes)
				)
			)
			(symbol "R_15k_0402_0_1"
				(rectangle
					(start 0.635 0.889)
					(end 4.445 -0.889)
					(stroke
						(width 0.254)
						(type default)
					)
					(fill
						(type none)
					)
				)
			)
			(symbol "R_15k_0402_1_1"
				(pin passive line
					(at 0 0 0)
					(length 0.635)
					(name "~"
						(effects
							(font
								(size 1.27 1.27)
							)
						)
					)
					(number "1"
						(effects
							(font
								(size 1.27 1.27)
							)
						)
					)
				)
				(pin passive line
					(at 5.08 0 180)
					(length 0.635)
					(name "~"
						(effects
							(font
								(size 1.27 1.27)
							)
						)
					)
					(number "2"
						(effects
							(font
								(size 1.27 1.27)
							)
						)
					)
				)
			)
		)
	(symbol "antmicroResistors0402:R_1k5_0402"
			(pin_numbers
				(hide yes)
			)
			(pin_names
				(hide yes)
			)
			(exclude_from_sim no)
			(in_bom yes)
			(on_board yes)
			(property "Reference" "R"
				(at 20.32 -5.08 0)
				(effects
					(font
						(size 1.27 1.27)
						(thickness 0.15)
					)
					(justify left bottom)
				)
			)
			(property "Value" "R_1k5_0402"
				(at 20.32 -12.7 0)
				(effects
					(font
						(size 1.27 1.27)
						(thickness 0.15)
					)
					(justify left bottom)
					(hide yes)
				)
			)
			(property "Footprint" "antmicro-footprints:R_0402_1005Metric"
				(at 20.32 -15.24 0)
				(effects
					(font
						(size 1.27 1.27)
						(thickness 0.15)
					)
					(justify left bottom)
					(hide yes)
				)
			)
			(property "Datasheet" "https://www.bourns.com/docs/product-datasheets/cr.pdf"
				(at 20.32 -17.78 0)
				(effects
					(font
						(size 1.27 1.27)
						(thickness 0.15)
					)
					(justify left bottom)
					(hide yes)
				)
			)
			(property "Description" "SMD Chip Resistor, 1.5 kohm, ± 1%, 62.5 mW, 0402 [1005 Metric], Thick Film, General Purpose"
				(at 0 0 0)
				(effects
					(font
						(size 1.27 1.27)
					)
					(hide yes)
				)
			)
			(property "MPN" "CR0402-FX-1501GLF"
				(at 20.32 -20.32 0)
				(effects
					(font
						(size 1.27 1.27)
						(thickness 0.15)
					)
					(justify left bottom)
					(hide yes)
				)
			)
			(property "Manufacturer" "Bourns"
				(at 20.32 -22.86 0)
				(effects
					(font
						(size 1.27 1.27)
						(thickness 0.15)
					)
					(justify left bottom)
					(hide yes)
				)
			)
			(property "License" "Apache-2.0"
				(at 20.32 -25.4 0)
				(effects
					(font
						(size 1.27 1.27)
						(thickness 0.15)
					)
					(justify left bottom)
					(hide yes)
				)
			)
			(property "Author" "Antmicro"
				(at 20.32 -27.94 0)
				(effects
					(font
						(size 1.27 1.27)
						(thickness 0.15)
					)
					(justify left bottom)
					(hide yes)
				)
			)
			(property "Val" "1k5"
				(at 20.32 -7.62 0)
				(effects
					(font
						(size 1.27 1.27)
						(thickness 0.15)
					)
					(justify left bottom)
				)
			)
			(property "Tolerance" "1%"
				(at 20.32 -10.16 0)
				(effects
					(font
						(size 1.27 1.27)
					)
					(justify left bottom)
					(hide yes)
				)
			)
			(property "ki_keywords" "0402, SMT, RESISTOR, PASSIVE"
				(at 0 0 0)
				(effects
					(font
						(size 1.27 1.27)
					)
					(hide yes)
				)
			)
			(symbol "R_1k5_0402_0_1"
				(rectangle
					(start 0.635 0.889)
					(end 4.445 -0.889)
					(stroke
						(width 0.254)
						(type default)
					)
					(fill
						(type none)
					)
				)
			)
			(symbol "R_1k5_0402_1_1"
				(pin passive line
					(at 0 0 0)
					(length 0.635)
					(name "~"
						(effects
							(font
								(size 1.27 1.27)
							)
						)
					)
					(number "1"
						(effects
							(font
								(size 1.27 1.27)
							)
						)
					)
				)
				(pin passive line
					(at 5.08 0 180)
					(length 0.635)
					(name "~"
						(effects
							(font
								(size 1.27 1.27)
							)
						)
					)
					(number "2"
						(effects
							(font
								(size 1.27 1.27)
							)
						)
					)
				)
			)
		)
	(symbol "antmicroResistors0402:R_1k_0402"
			(pin_numbers
				(hide yes)
			)
			(pin_names
				(hide yes)
			)
			(exclude_from_sim no)
			(in_bom yes)
			(on_board yes)
			(property "Reference" "R"
				(at 20.32 -5.08 0)
				(effects
					(font
						(size 1.27 1.27)
						(thickness 0.15)
					)
					(justify left bottom)
				)
			)
			(property "Value" "R_1k_0402"
				(at 20.32 -12.7 0)
				(effects
					(font
						(size 1.27 1.27)
						(thickness 0.15)
					)
					(justify left bottom)
					(hide yes)
				)
			)
			(property "Footprint" "antmicro-footprints:R_0402_1005Metric"
				(at 20.32 -15.24 0)
				(effects
					(font
						(size 1.27 1.27)
						(thickness 0.15)
					)
					(justify left bottom)
					(hide yes)
				)
			)
			(property "Datasheet" "https://www.bourns.com/docs/product-datasheets/cr.pdf"
				(at 20.32 -17.78 0)
				(effects
					(font
						(size 1.27 1.27)
						(thickness 0.15)
					)
					(justify left bottom)
					(hide yes)
				)
			)
			(property "Description" "SMD Chip Resistor, 1 kohm, ± 1%, 63 mW, 0402 [1005 Metric], Thick Film, General Purpose"
				(at 0 0 0)
				(effects
					(font
						(size 1.27 1.27)
					)
					(hide yes)
				)
			)
			(property "MPN" "CR0402-FX-1001GLF"
				(at 20.32 -20.32 0)
				(effects
					(font
						(size 1.27 1.27)
						(thickness 0.15)
					)
					(justify left bottom)
					(hide yes)
				)
			)
			(property "Manufacturer" "Bourns"
				(at 20.32 -22.86 0)
				(effects
					(font
						(size 1.27 1.27)
						(thickness 0.15)
					)
					(justify left bottom)
					(hide yes)
				)
			)
			(property "License" "Apache-2.0"
				(at 20.32 -25.4 0)
				(effects
					(font
						(size 1.27 1.27)
						(thickness 0.15)
					)
					(justify left bottom)
					(hide yes)
				)
			)
			(property "Author" "Antmicro"
				(at 20.32 -27.94 0)
				(effects
					(font
						(size 1.27 1.27)
						(thickness 0.15)
					)
					(justify left bottom)
					(hide yes)
				)
			)
			(property "Val" "1k"
				(at 20.32 -7.62 0)
				(effects
					(font
						(size 1.27 1.27)
						(thickness 0.15)
					)
					(justify left bottom)
				)
			)
			(property "Tolerance" "1%"
				(at 20.32 -10.16 0)
				(effects
					(font
						(size 1.27 1.27)
					)
					(justify left bottom)
					(hide yes)
				)
			)
			(property "ki_keywords" "0402, SMT, RESISTOR, PASSIVE"
				(at 0 0 0)
				(effects
					(font
						(size 1.27 1.27)
					)
					(hide yes)
				)
			)
			(symbol "R_1k_0402_0_1"
				(rectangle
					(start 0.635 0.889)
					(end 4.445 -0.889)
					(stroke
						(width 0.254)
						(type default)
					)
					(fill
						(type none)
					)
				)
			)
			(symbol "R_1k_0402_1_1"
				(pin passive line
					(at 0 0 0)
					(length 0.635)
					(name "~"
						(effects
							(font
								(size 1.27 1.27)
							)
						)
					)
					(number "1"
						(effects
							(font
								(size 1.27 1.27)
							)
						)
					)
				)
				(pin passive line
					(at 5.08 0 180)
					(length 0.635)
					(name "~"
						(effects
							(font
								(size 1.27 1.27)
							)
						)
					)
					(number "2"
						(effects
							(font
								(size 1.27 1.27)
							)
						)
					)
				)
			)
		)
	(symbol "antmicroResistors0402:R_22R_0402"
			(pin_numbers
				(hide yes)
			)
			(pin_names
				(hide yes)
			)
			(exclude_from_sim no)
			(in_bom yes)
			(on_board yes)
			(property "Reference" "R"
				(at 20.32 -5.08 0)
				(effects
					(font
						(size 1.27 1.27)
						(thickness 0.15)
					)
					(justify left bottom)
				)
			)
			(property "Value" "R_22R_0402"
				(at 20.32 -12.7 0)
				(effects
					(font
						(size 1.27 1.27)
						(thickness 0.15)
					)
					(justify left bottom)
					(hide yes)
				)
			)
			(property "Footprint" "antmicro-footprints:R_0402_1005Metric"
				(at 20.32 -15.24 0)
				(effects
					(font
						(size 1.27 1.27)
						(thickness 0.15)
					)
					(justify left bottom)
					(hide yes)
				)
			)
			(property "Datasheet" "https://www.bourns.com/docs/product-datasheets/cr.pdf"
				(at 20.32 -17.78 0)
				(effects
					(font
						(size 1.27 1.27)
						(thickness 0.15)
					)
					(justify left bottom)
					(hide yes)
				)
			)
			(property "Description" "SMD Chip Resistor, 22 ohm, ± 1%, 62.5 mW, 0402 [1005 Metric], Thick Film, General Purpose"
				(at 0 0 0)
				(effects
					(font
						(size 1.27 1.27)
					)
					(hide yes)
				)
			)
			(property "MPN" "CR0402-FX-22R0GLF"
				(at 20.32 -20.32 0)
				(effects
					(font
						(size 1.27 1.27)
						(thickness 0.15)
					)
					(justify left bottom)
					(hide yes)
				)
			)
			(property "Manufacturer" "Bourns"
				(at 20.32 -22.86 0)
				(effects
					(font
						(size 1.27 1.27)
						(thickness 0.15)
					)
					(justify left bottom)
					(hide yes)
				)
			)
			(property "License" "Apache-2.0"
				(at 20.32 -25.4 0)
				(effects
					(font
						(size 1.27 1.27)
						(thickness 0.15)
					)
					(justify left bottom)
					(hide yes)
				)
			)
			(property "Author" "Antmicro"
				(at 20.32 -27.94 0)
				(effects
					(font
						(size 1.27 1.27)
						(thickness 0.15)
					)
					(justify left bottom)
					(hide yes)
				)
			)
			(property "Val" "22R"
				(at 20.32 -7.62 0)
				(effects
					(font
						(size 1.27 1.27)
						(thickness 0.15)
					)
					(justify left bottom)
				)
			)
			(property "Tolerance" "1%"
				(at 20.32 -10.16 0)
				(effects
					(font
						(size 1.27 1.27)
					)
					(justify left bottom)
					(hide yes)
				)
			)
			(property "ki_keywords" "0402, SMT, RESISTOR, PASSIVE"
				(at 0 0 0)
				(effects
					(font
						(size 1.27 1.27)
					)
					(hide yes)
				)
			)
			(symbol "R_22R_0402_0_1"
				(rectangle
					(start 0.635 0.889)
					(end 4.445 -0.889)
					(stroke
						(width 0.254)
						(type default)
					)
					(fill
						(type none)
					)
				)
			)
			(symbol "R_22R_0402_1_1"
				(pin passive line
					(at 0 0 0)
					(length 0.635)
					(name "~"
						(effects
							(font
								(size 1.27 1.27)
							)
						)
					)
					(number "1"
						(effects
							(font
								(size 1.27 1.27)
							)
						)
					)
				)
				(pin passive line
					(at 5.08 0 180)
					(length 0.635)
					(name "~"
						(effects
							(font
								(size 1.27 1.27)
							)
						)
					)
					(number "2"
						(effects
							(font
								(size 1.27 1.27)
							)
						)
					)
				)
			)
		)
	(symbol "antmicroResistors0402:R_2k_0402"
			(pin_numbers
				(hide yes)
			)
			(pin_names
				(hide yes)
			)
			(exclude_from_sim no)
			(in_bom yes)
			(on_board yes)
			(property "Reference" "R"
				(at 20.32 -5.08 0)
				(effects
					(font
						(size 1.27 1.27)
						(thickness 0.15)
					)
					(justify left bottom)
				)
			)
			(property "Value" "R_2k_0402"
				(at 20.32 -12.7 0)
				(effects
					(font
						(size 1.27 1.27)
						(thickness 0.15)
					)
					(justify left bottom)
					(hide yes)
				)
			)
			(property "Footprint" "antmicro-footprints:R_0402_1005Metric"
				(at 20.32 -15.24 0)
				(effects
					(font
						(size 1.27 1.27)
						(thickness 0.15)
					)
					(justify left bottom)
					(hide yes)
				)
			)
			(property "Datasheet" "https://www.bourns.com/docs/product-datasheets/cr.pdf"
				(at 20.32 -17.78 0)
				(effects
					(font
						(size 1.27 1.27)
						(thickness 0.15)
					)
					(justify left bottom)
					(hide yes)
				)
			)
			(property "Description" "SMD Chip Resistor, 2 kohm, ± 1%, 62.5 mW, 0402 [1005 Metric], Thick Film, General Purpose"
				(at 0 0 0)
				(effects
					(font
						(size 1.27 1.27)
					)
					(hide yes)
				)
			)
			(property "MPN" "CR0402-FX-2001GLF"
				(at 20.32 -20.32 0)
				(effects
					(font
						(size 1.27 1.27)
						(thickness 0.15)
					)
					(justify left bottom)
					(hide yes)
				)
			)
			(property "Manufacturer" "Bourns"
				(at 20.32 -22.86 0)
				(effects
					(font
						(size 1.27 1.27)
						(thickness 0.15)
					)
					(justify left bottom)
					(hide yes)
				)
			)
			(property "License" "Apache-2.0"
				(at 20.32 -25.4 0)
				(effects
					(font
						(size 1.27 1.27)
						(thickness 0.15)
					)
					(justify left bottom)
					(hide yes)
				)
			)
			(property "Author" "Antmicro"
				(at 20.32 -27.94 0)
				(effects
					(font
						(size 1.27 1.27)
						(thickness 0.15)
					)
					(justify left bottom)
					(hide yes)
				)
			)
			(property "Val" "2k"
				(at 20.32 -7.62 0)
				(effects
					(font
						(size 1.27 1.27)
						(thickness 0.15)
					)
					(justify left bottom)
				)
			)
			(property "Tolerance" "1%"
				(at 20.32 -10.16 0)
				(effects
					(font
						(size 1.27 1.27)
					)
					(justify left bottom)
					(hide yes)
				)
			)
			(property "ki_keywords" "0402, SMT, RESISTOR, PASSIVE"
				(at 0 0 0)
				(effects
					(font
						(size 1.27 1.27)
					)
					(hide yes)
				)
			)
			(symbol "R_2k_0402_0_1"
				(rectangle
					(start 0.635 0.889)
					(end 4.445 -0.889)
					(stroke
						(width 0.254)
						(type default)
					)
					(fill
						(type none)
					)
				)
			)
			(symbol "R_2k_0402_1_1"
				(pin passive line
					(at 0 0 0)
					(length 0.635)
					(name "~"
						(effects
							(font
								(size 1.27 1.27)
							)
						)
					)
					(number "1"
						(effects
							(font
								(size 1.27 1.27)
							)
						)
					)
				)
				(pin passive line
					(at 5.08 0 180)
					(length 0.635)
					(name "~"
						(effects
							(font
								(size 1.27 1.27)
							)
						)
					)
					(number "2"
						(effects
							(font
								(size 1.27 1.27)
							)
						)
					)
				)
			)
		)
	(symbol "antmicroResistors0402:R_49k9_0402"
			(pin_numbers
				(hide yes)
			)
			(pin_names
				(hide yes)
			)
			(exclude_from_sim no)
			(in_bom yes)
			(on_board yes)
			(property "Reference" "R"
				(at 20.32 -5.08 0)
				(effects
					(font
						(size 1.27 1.27)
						(thickness 0.15)
					)
					(justify left bottom)
				)
			)
			(property "Value" "R_49k9_0402"
				(at 20.32 -12.7 0)
				(effects
					(font
						(size 1.27 1.27)
						(thickness 0.15)
					)
					(justify left bottom)
					(hide yes)
				)
			)
			(property "Footprint" "antmicro-footprints:R_0402_1005Metric"
				(at 20.32 -15.24 0)
				(effects
					(font
						(size 1.27 1.27)
						(thickness 0.15)
					)
					(justify left bottom)
					(hide yes)
				)
			)
			(property "Datasheet" "https://www.bourns.com/docs/product-datasheets/cr.pdf"
				(at 20.32 -17.78 0)
				(effects
					(font
						(size 1.27 1.27)
						(thickness 0.15)
					)
					(justify left bottom)
					(hide yes)
				)
			)
			(property "Description" "SMD Chip Resistor, 49.9 kohm, ± 1%, 63 mW, 0402 [1005 Metric], Thick Film, General Purpose"
				(at 0 0 0)
				(effects
					(font
						(size 1.27 1.27)
					)
					(hide yes)
				)
			)
			(property "MPN" "CR0402-FX-4992GLF"
				(at 20.32 -20.32 0)
				(effects
					(font
						(size 1.27 1.27)
						(thickness 0.15)
					)
					(justify left bottom)
					(hide yes)
				)
			)
			(property "Manufacturer" "Bourns"
				(at 20.32 -22.86 0)
				(effects
					(font
						(size 1.27 1.27)
						(thickness 0.15)
					)
					(justify left bottom)
					(hide yes)
				)
			)
			(property "License" "Apache-2.0"
				(at 20.32 -25.4 0)
				(effects
					(font
						(size 1.27 1.27)
						(thickness 0.15)
					)
					(justify left bottom)
					(hide yes)
				)
			)
			(property "Author" "Antmicro"
				(at 20.32 -27.94 0)
				(effects
					(font
						(size 1.27 1.27)
						(thickness 0.15)
					)
					(justify left bottom)
					(hide yes)
				)
			)
			(property "Val" "49k9"
				(at 20.32 -7.62 0)
				(effects
					(font
						(size 1.27 1.27)
						(thickness 0.15)
					)
					(justify left bottom)
				)
			)
			(property "Tolerance" "1%"
				(at 20.32 -10.16 0)
				(effects
					(font
						(size 1.27 1.27)
					)
					(justify left bottom)
					(hide yes)
				)
			)
			(property "ki_keywords" "0402, SMT, RESISTOR, PASSIVE"
				(at 0 0 0)
				(effects
					(font
						(size 1.27 1.27)
					)
					(hide yes)
				)
			)
			(symbol "R_49k9_0402_0_1"
				(rectangle
					(start 0.635 0.889)
					(end 4.445 -0.889)
					(stroke
						(width 0.254)
						(type default)
					)
					(fill
						(type none)
					)
				)
			)
			(symbol "R_49k9_0402_1_1"
				(pin passive line
					(at 0 0 0)
					(length 0.635)
					(name "~"
						(effects
							(font
								(size 1.27 1.27)
							)
						)
					)
					(number "1"
						(effects
							(font
								(size 1.27 1.27)
							)
						)
					)
				)
				(pin passive line
					(at 5.08 0 180)
					(length 0.635)
					(name "~"
						(effects
							(font
								(size 1.27 1.27)
							)
						)
					)
					(number "2"
						(effects
							(font
								(size 1.27 1.27)
							)
						)
					)
				)
			)
		)
	(symbol "antmicroResistors0402:R_50R_0402"
			(pin_numbers
				(hide yes)
			)
			(pin_names
				(hide yes)
			)
			(exclude_from_sim no)
			(in_bom yes)
			(on_board yes)
			(property "Reference" "R"
				(at 20.32 -5.08 0)
				(effects
					(font
						(size 1.27 1.27)
						(thickness 0.15)
					)
					(justify left bottom)
				)
			)
			(property "Value" "R_50R_0402"
				(at 20.32 -12.7 0)
				(effects
					(font
						(size 1.27 1.27)
						(thickness 0.15)
					)
					(justify left bottom)
					(hide yes)
				)
			)
			(property "Footprint" "antmicro-footprints:R_0402_1005Metric"
				(at 20.32 -15.24 0)
				(effects
					(font
						(size 1.27 1.27)
						(thickness 0.15)
					)
					(justify left bottom)
					(hide yes)
				)
			)
			(property "Datasheet" "https://www.bourns.com/docs/product-datasheets/cr.pdf"
				(at 20.32 -17.78 0)
				(effects
					(font
						(size 1.27 1.27)
						(thickness 0.15)
					)
					(justify left bottom)
					(hide yes)
				)
			)
			(property "Description" "SMD Chip Resistor"
				(at 0 0 0)
				(effects
					(font
						(size 1.27 1.27)
					)
					(hide yes)
				)
			)
			(property "MPN" "CR0402-FX-50R0GLF"
				(at 20.32 -20.32 0)
				(effects
					(font
						(size 1.27 1.27)
						(thickness 0.15)
					)
					(justify left bottom)
					(hide yes)
				)
			)
			(property "Manufacturer" "Bourns"
				(at 20.32 -22.86 0)
				(effects
					(font
						(size 1.27 1.27)
						(thickness 0.15)
					)
					(justify left bottom)
					(hide yes)
				)
			)
			(property "License" "Apache-2.0"
				(at 20.32 -25.4 0)
				(effects
					(font
						(size 1.27 1.27)
						(thickness 0.15)
					)
					(justify left bottom)
					(hide yes)
				)
			)
			(property "Author" "Antmicro"
				(at 20.32 -27.94 0)
				(effects
					(font
						(size 1.27 1.27)
						(thickness 0.15)
					)
					(justify left bottom)
					(hide yes)
				)
			)
			(property "Val" "50R"
				(at 20.32 -7.62 0)
				(effects
					(font
						(size 1.27 1.27)
						(thickness 0.15)
					)
					(justify left bottom)
				)
			)
			(property "Tolerance" "1%"
				(at 20.32 -10.16 0)
				(effects
					(font
						(size 1.27 1.27)
					)
					(justify left bottom)
					(hide yes)
				)
			)
			(property "ki_keywords" "0402, SMT, RESISTOR, PASSIVE"
				(at 0 0 0)
				(effects
					(font
						(size 1.27 1.27)
					)
					(hide yes)
				)
			)
			(symbol "R_50R_0402_0_1"
				(rectangle
					(start 0.635 0.889)
					(end 4.445 -0.889)
					(stroke
						(width 0.254)
						(type default)
					)
					(fill
						(type none)
					)
				)
			)
			(symbol "R_50R_0402_1_1"
				(pin passive line
					(at 0 0 0)
					(length 0.635)
					(name "~"
						(effects
							(font
								(size 1.27 1.27)
							)
						)
					)
					(number "1"
						(effects
							(font
								(size 1.27 1.27)
							)
						)
					)
				)
				(pin passive line
					(at 5.08 0 180)
					(length 0.635)
					(name "~"
						(effects
							(font
								(size 1.27 1.27)
							)
						)
					)
					(number "2"
						(effects
							(font
								(size 1.27 1.27)
							)
						)
					)
				)
			)
		)
	(symbol "antmicroResistors0402:R_68k_0402"
			(pin_numbers
				(hide yes)
			)
			(pin_names
				(hide yes)
			)
			(exclude_from_sim no)
			(in_bom yes)
			(on_board yes)
			(property "Reference" "R"
				(at 20.32 -5.08 0)
				(effects
					(font
						(size 1.27 1.27)
						(thickness 0.15)
					)
					(justify left bottom)
				)
			)
			(property "Value" "R_68k_0402"
				(at 20.32 -12.7 0)
				(effects
					(font
						(size 1.27 1.27)
						(thickness 0.15)
					)
					(justify left bottom)
					(hide yes)
				)
			)
			(property "Footprint" "antmicro-footprints:R_0402_1005Metric"
				(at 20.32 -15.24 0)
				(effects
					(font
						(size 1.27 1.27)
						(thickness 0.15)
					)
					(justify left bottom)
					(hide yes)
				)
			)
			(property "Datasheet" "https://www.bourns.com/docs/product-datasheets/cr.pdf"
				(at 20.32 -17.78 0)
				(effects
					(font
						(size 1.27 1.27)
						(thickness 0.15)
					)
					(justify left bottom)
					(hide yes)
				)
			)
			(property "Description" "SMD Chip Resistor"
				(at 0 0 0)
				(effects
					(font
						(size 1.27 1.27)
					)
					(hide yes)
				)
			)
			(property "MPN" "CR0402-FX-6802GLF"
				(at 20.32 -20.32 0)
				(effects
					(font
						(size 1.27 1.27)
						(thickness 0.15)
					)
					(justify left bottom)
					(hide yes)
				)
			)
			(property "Manufacturer" "Bourns"
				(at 20.32 -22.86 0)
				(effects
					(font
						(size 1.27 1.27)
						(thickness 0.15)
					)
					(justify left bottom)
					(hide yes)
				)
			)
			(property "License" "Apache-2.0"
				(at 20.32 -25.4 0)
				(effects
					(font
						(size 1.27 1.27)
						(thickness 0.15)
					)
					(justify left bottom)
					(hide yes)
				)
			)
			(property "Author" "Antmicro"
				(at 20.32 -27.94 0)
				(effects
					(font
						(size 1.27 1.27)
						(thickness 0.15)
					)
					(justify left bottom)
					(hide yes)
				)
			)
			(property "Val" "68k"
				(at 20.32 -7.62 0)
				(effects
					(font
						(size 1.27 1.27)
						(thickness 0.15)
					)
					(justify left bottom)
				)
			)
			(property "Tolerance" "1%"
				(at 20.32 -10.16 0)
				(effects
					(font
						(size 1.27 1.27)
					)
					(justify left bottom)
					(hide yes)
				)
			)
			(property "ki_keywords" "0402, SMT, RESISTOR, PASSIVE"
				(at 0 0 0)
				(effects
					(font
						(size 1.27 1.27)
					)
					(hide yes)
				)
			)
			(symbol "R_68k_0402_0_1"
				(rectangle
					(start 0.635 0.889)
					(end 4.445 -0.889)
					(stroke
						(width 0.254)
						(type default)
					)
					(fill
						(type none)
					)
				)
			)
			(symbol "R_68k_0402_1_1"
				(pin passive line
					(at 0 0 0)
					(length 0.635)
					(name "~"
						(effects
							(font
								(size 1.27 1.27)
							)
						)
					)
					(number "1"
						(effects
							(font
								(size 1.27 1.27)
							)
						)
					)
				)
				(pin passive line
					(at 5.08 0 180)
					(length 0.635)
					(name "~"
						(effects
							(font
								(size 1.27 1.27)
							)
						)
					)
					(number "2"
						(effects
							(font
								(size 1.27 1.27)
							)
						)
					)
				)
			)
		)
	(symbol "antmicroResistors0603:R_0R_22.4A_0603"
			(pin_numbers
				(hide yes)
			)
			(pin_names
				(hide yes)
			)
			(exclude_from_sim no)
			(in_bom yes)
			(on_board yes)
			(property "Reference" "R"
				(at 15.24 -2.54 0)
				(effects
					(font
						(size 1.27 1.27)
						(thickness 0.15)
					)
					(justify left bottom)
				)
			)
			(property "Value" "R_0R_22.4A_0603"
				(at 15.24 -5.08 0)
				(effects
					(font
						(size 1.27 1.27)
						(thickness 0.15)
					)
					(justify left bottom)
				)
			)
			(property "Footprint" "antmicro-footprints:R_0603_1608Metric"
				(at 15.24 -10.16 0)
				(effects
					(font
						(size 1.27 1.27)
						(thickness 0.15)
					)
					(justify left bottom)
					(hide yes)
				)
			)
			(property "Datasheet" "https://fscdn.rohm.com/en/products/databook/datasheet/passive/resistor/chip_resistor/pmr-jpw-e.pdf"
				(at 15.24 -12.7 0)
				(effects
					(font
						(size 1.27 1.27)
						(thickness 0.15)
					)
					(justify left bottom)
					(hide yes)
				)
			)
			(property "Description" "SMD Chip Resistor"
				(at 0 0 0)
				(effects
					(font
						(size 1.27 1.27)
					)
					(hide yes)
				)
			)
			(property "MPN" "PMR03EZPJ000"
				(at 15.24 -15.24 0)
				(effects
					(font
						(size 1.27 1.27)
						(thickness 0.15)
					)
					(justify left bottom)
					(hide yes)
				)
			)
			(property "Manufacturer" "ROHM Semiconductor"
				(at 15.24 -17.78 0)
				(effects
					(font
						(size 1.27 1.27)
						(thickness 0.15)
					)
					(justify left bottom)
					(hide yes)
				)
			)
			(property "Val" "0R"
				(at 15.24 -7.62 0)
				(effects
					(font
						(size 1.27 1.27)
						(thickness 0.15)
					)
					(justify left bottom)
				)
			)
			(property "Max. Curr." "22.4A"
				(at 15.24 -20.32 0)
				(effects
					(font
						(size 1.27 1.27)
						(thickness 0.15)
					)
					(justify left bottom)
				)
			)
			(property "Author" "Antmicro"
				(at 15.24 -22.86 0)
				(effects
					(font
						(size 1.27 1.27)
						(thickness 0.15)
					)
					(justify left bottom)
					(hide yes)
				)
			)
			(property "License" "Apache-2.0"
				(at 15.24 -25.4 0)
				(effects
					(font
						(size 1.27 1.27)
						(thickness 0.15)
					)
					(justify left bottom)
					(hide yes)
				)
			)
			(property "Tolerance" "template_tolerance"
				(at 20.32 -10.16 0)
				(effects
					(font
						(size 1.27 1.27)
					)
					(justify left bottom)
					(hide yes)
				)
			)
			(property "ki_keywords" "0603, SMT, RESISTOR, PASSIVE"
				(at 0 0 0)
				(effects
					(font
						(size 1.27 1.27)
					)
					(hide yes)
				)
			)
			(symbol "R_0R_22.4A_0603_0_1"
				(rectangle
					(start 0.635 0.889)
					(end 4.445 -0.889)
					(stroke
						(width 0.254)
						(type default)
					)
					(fill
						(type none)
					)
				)
			)
			(symbol "R_0R_22.4A_0603_1_1"
				(pin passive line
					(at 0 0 0)
					(length 0.635)
					(name "~"
						(effects
							(font
								(size 1.27 1.27)
							)
						)
					)
					(number "1"
						(effects
							(font
								(size 1.27 1.27)
							)
						)
					)
				)
				(pin passive line
					(at 5.08 0 180)
					(length 0.635)
					(name "~"
						(effects
							(font
								(size 1.27 1.27)
							)
						)
					)
					(number "2"
						(effects
							(font
								(size 1.27 1.27)
							)
						)
					)
				)
			)
		)
	(symbol "antmicroTVSDiodes:ESD204DQAR"
			(exclude_from_sim no)
			(in_bom yes)
			(on_board yes)
			(property "Reference" "D"
				(at 24.13 0 0)
				(effects
					(font
						(size 1.27 1.27)
						(thickness 0.15)
					)
					(justify left bottom)
				)
			)
			(property "Value" "ESD204DQAR"
				(at 24.13 -5.08 0)
				(effects
					(font
						(size 1.27 1.27)
						(thickness 0.15)
					)
					(justify left bottom)
					(hide yes)
				)
			)
			(property "Footprint" "antmicro-footprints:USON-10_2.5x1mm_P0.5mm"
				(at 24.13 -7.62 0)
				(effects
					(font
						(size 1.27 1.27)
						(thickness 0.15)
					)
					(justify left bottom)
					(hide yes)
				)
			)
			(property "Datasheet" "https://www.ti.com/lit/ds/symlink/esd204.pdf?ts=1706004844383&ref_url=https%253A%252F%252Fwww.ti.com%252Finterface%252Fdiodes%252Fesd-protection-diodes%252Fproducts.html"
				(at 24.13 -10.16 0)
				(effects
					(font
						(size 1.27 1.27)
						(thickness 0.15)
					)
					(justify left bottom)
					(hide yes)
				)
			)
			(property "Description" "TVS diode array, 30 kV, USON-10, 3.6 V, 0.55 pF"
				(at 24.13 -20.32 0)
				(effects
					(font
						(size 1.27 1.27)
					)
					(justify left bottom)
					(hide yes)
				)
			)
			(property "MPN" "ESD204DQAR"
				(at 24.13 -2.54 0)
				(effects
					(font
						(size 1.27 1.27)
						(thickness 0.15)
					)
					(justify left bottom)
				)
			)
			(property "Manufacturer" "Texas Instruments"
				(at 24.13 -12.7 0)
				(effects
					(font
						(size 1.27 1.27)
						(thickness 0.15)
					)
					(justify left bottom)
					(hide yes)
				)
			)
			(property "Author" "Antmicro"
				(at 24.13 -15.24 0)
				(effects
					(font
						(size 1.27 1.27)
						(thickness 0.15)
					)
					(justify left bottom)
					(hide yes)
				)
			)
			(property "License" "Apache-2.0"
				(at 24.13 -17.78 0)
				(effects
					(font
						(size 1.27 1.27)
						(thickness 0.15)
					)
					(justify left bottom)
					(hide yes)
				)
			)
			(property "ki_keywords" "SMT, DIODE, SEMICONDUCTOR, TVS, ESD"
				(at 0 0 0)
				(effects
					(font
						(size 1.27 1.27)
					)
					(hide yes)
				)
			)
			(symbol "ESD204DQAR_1_1"
				(rectangle
					(start 2.54 2.54)
					(end 8.89 -12.7)
					(stroke
						(width 0.254)
						(type default)
					)
					(fill
						(type background)
					)
				)
				(polyline
					(pts
						(xy 2.54 0) (xy 7.62 0)
					)
					(stroke
						(width 0.254)
						(type default)
					)
					(fill
						(type background)
					)
				)
				(polyline
					(pts
						(xy 2.54 -2.54) (xy 7.62 -2.54)
					)
					(stroke
						(width 0.254)
						(type default)
					)
					(fill
						(type background)
					)
				)
				(polyline
					(pts
						(xy 2.54 -5.08) (xy 7.62 -5.08)
					)
					(stroke
						(width 0.254)
						(type default)
					)
					(fill
						(type background)
					)
				)
				(polyline
					(pts
						(xy 2.54 -7.62) (xy 7.62 -7.62)
					)
					(stroke
						(width 0.254)
						(type default)
					)
					(fill
						(type background)
					)
				)
				(polyline
					(pts
						(xy 4.826 -0.635) (xy 5.08 -0.381) (xy 5.08 0.381) (xy 5.334 0.635)
					)
					(stroke
						(width 0.254)
						(type default)
					)
					(fill
						(type background)
					)
				)
				(polyline
					(pts
						(xy 4.826 -3.175) (xy 5.08 -2.921) (xy 5.08 -2.159) (xy 5.334 -1.905)
					)
					(stroke
						(width 0.254)
						(type default)
					)
					(fill
						(type background)
					)
				)
				(polyline
					(pts
						(xy 4.826 -5.715) (xy 5.08 -5.461) (xy 5.08 -4.699) (xy 5.334 -4.445)
					)
					(stroke
						(width 0.254)
						(type default)
					)
					(fill
						(type background)
					)
				)
				(polyline
					(pts
						(xy 4.826 -8.255) (xy 5.08 -8.001) (xy 5.08 -7.239) (xy 5.334 -6.985)
					)
					(stroke
						(width 0.254)
						(type default)
					)
					(fill
						(type background)
					)
				)
				(polyline
					(pts
						(xy 5.08 0) (xy 3.81 -0.635) (xy 3.81 0.635) (xy 5.08 0)
					)
					(stroke
						(width 0.254)
						(type default)
					)
					(fill
						(type background)
					)
				)
				(polyline
					(pts
						(xy 5.08 0) (xy 6.35 -0.635) (xy 6.35 0.635) (xy 5.08 0)
					)
					(stroke
						(width 0.254)
						(type default)
					)
					(fill
						(type background)
					)
				)
				(polyline
					(pts
						(xy 5.08 -2.54) (xy 3.81 -3.175) (xy 3.81 -1.905) (xy 5.08 -2.54)
					)
					(stroke
						(width 0.254)
						(type default)
					)
					(fill
						(type background)
					)
				)
				(polyline
					(pts
						(xy 5.08 -2.54) (xy 6.35 -3.175) (xy 6.35 -1.905) (xy 5.08 -2.54)
					)
					(stroke
						(width 0.254)
						(type default)
					)
					(fill
						(type background)
					)
				)
				(polyline
					(pts
						(xy 5.08 -5.08) (xy 3.81 -5.715) (xy 3.81 -4.445) (xy 5.08 -5.08)
					)
					(stroke
						(width 0.254)
						(type default)
					)
					(fill
						(type background)
					)
				)
				(polyline
					(pts
						(xy 5.08 -5.08) (xy 6.35 -4.445) (xy 6.35 -5.715) (xy 5.08 -5.08)
					)
					(stroke
						(width 0.254)
						(type default)
					)
					(fill
						(type background)
					)
				)
				(polyline
					(pts
						(xy 5.08 -7.62) (xy 3.81 -8.255) (xy 3.81 -6.985) (xy 5.08 -7.62)
					)
					(stroke
						(width 0.254)
						(type default)
					)
					(fill
						(type background)
					)
				)
				(polyline
					(pts
						(xy 6.35 -6.985) (xy 6.35 -8.255) (xy 5.08 -7.62) (xy 6.35 -6.985)
					)
					(stroke
						(width 0.254)
						(type default)
					)
					(fill
						(type background)
					)
				)
				(polyline
					(pts
						(xy 7.62 0) (xy 7.62 -10.16)
					)
					(stroke
						(width 0.254)
						(type default)
					)
					(fill
						(type background)
					)
				)
				(circle
					(center 7.62 -2.54)
					(radius 0.254)
					(stroke
						(width 0.254)
						(type default)
					)
					(fill
						(type background)
					)
				)
				(circle
					(center 7.62 -5.08)
					(radius 0.254)
					(stroke
						(width 0.254)
						(type default)
					)
					(fill
						(type background)
					)
				)
				(circle
					(center 7.62 -5.08)
					(radius 0.254)
					(stroke
						(width 0.254)
						(type default)
					)
					(fill
						(type background)
					)
				)
				(circle
					(center 7.62 -7.62)
					(radius 0.254)
					(stroke
						(width 0.254)
						(type default)
					)
					(fill
						(type background)
					)
				)
				(polyline
					(pts
						(xy 7.62 -10.16) (xy 2.54 -10.16)
					)
					(stroke
						(width 0.254)
						(type default)
					)
					(fill
						(type background)
					)
				)
				(pin passive line
					(at 0 0 0)
					(length 2.54)
					(name "~"
						(effects
							(font
								(size 1.27 1.27)
							)
						)
					)
					(number "1"
						(effects
							(font
								(size 1.27 1.27)
							)
						)
					)
				)
				(pin passive line
					(at 0 0 0)
					(length 2.54)
					(hide yes)
					(name "~"
						(effects
							(font
								(size 1.27 1.27)
							)
						)
					)
					(number "10"
						(effects
							(font
								(size 1.27 1.27)
							)
						)
					)
				)
				(pin passive line
					(at 0 -2.54 0)
					(length 2.54)
					(name "~"
						(effects
							(font
								(size 1.27 1.27)
							)
						)
					)
					(number "2"
						(effects
							(font
								(size 1.27 1.27)
							)
						)
					)
				)
				(pin passive line
					(at 0 -2.54 0)
					(length 2.54)
					(hide yes)
					(name "~"
						(effects
							(font
								(size 1.27 1.27)
							)
						)
					)
					(number "9"
						(effects
							(font
								(size 1.27 1.27)
							)
						)
					)
				)
				(pin passive line
					(at 0 -5.08 0)
					(length 2.54)
					(name "~"
						(effects
							(font
								(size 1.27 1.27)
							)
						)
					)
					(number "4"
						(effects
							(font
								(size 1.27 1.27)
							)
						)
					)
				)
				(pin passive line
					(at 0 -5.08 0)
					(length 2.54)
					(hide yes)
					(name "~"
						(effects
							(font
								(size 1.27 1.27)
							)
						)
					)
					(number "7"
						(effects
							(font
								(size 1.27 1.27)
							)
						)
					)
				)
				(pin passive line
					(at 0 -7.62 0)
					(length 2.54)
					(name "~"
						(effects
							(font
								(size 1.27 1.27)
							)
						)
					)
					(number "5"
						(effects
							(font
								(size 1.27 1.27)
							)
						)
					)
				)
				(pin passive line
					(at 0 -7.62 0)
					(length 2.54)
					(hide yes)
					(name "~"
						(effects
							(font
								(size 1.27 1.27)
							)
						)
					)
					(number "6"
						(effects
							(font
								(size 1.27 1.27)
							)
						)
					)
				)
				(pin power_in line
					(at 0 -10.16 0)
					(length 2.54)
					(name "~"
						(effects
							(font
								(size 1.27 1.27)
							)
						)
					)
					(number "3"
						(effects
							(font
								(size 1.27 1.27)
							)
						)
					)
				)
				(pin passive line
					(at 0 -10.16 0)
					(length 2.54)
					(hide yes)
					(name "~"
						(effects
							(font
								(size 1.27 1.27)
							)
						)
					)
					(number "8"
						(effects
							(font
								(size 1.27 1.27)
							)
						)
					)
				)
			)
		)
	(symbol "antmicroTVSDiodes:ESDA25P35-1U1M"
			(pin_numbers
				(hide yes)
			)
			(pin_names
				(hide yes)
			)
			(exclude_from_sim no)
			(in_bom yes)
			(on_board yes)
			(property "Reference" "D"
				(at 24.13 -5.08 0)
				(effects
					(font
						(size 1.27 1.27)
						(thickness 0.15)
					)
					(justify left bottom)
				)
			)
			(property "Value" "ESDA25P35-1U1M"
				(at 24.13 -15.24 0)
				(effects
					(font
						(size 1.27 1.27)
						(thickness 0.15)
					)
					(justify left bottom)
					(hide yes)
				)
			)
			(property "Footprint" "antmicro-footprints:QFN-2L_1.6x1x0.55mm"
				(at 24.13 -10.16 0)
				(effects
					(font
						(size 1.27 1.27)
						(thickness 0.15)
					)
					(justify left bottom)
					(hide yes)
				)
			)
			(property "Datasheet" "https://www.st.com/resource/en/datasheet/esda25p35-1u1m.pdf"
				(at 24.13 -12.7 0)
				(effects
					(font
						(size 1.27 1.27)
						(thickness 0.15)
					)
					(justify left bottom)
					(hide yes)
				)
			)
			(property "Description" "Unidirectional TVS, 30 kV, QFN-2L, 22 V, 195 pF"
				(at 0 0 0)
				(effects
					(font
						(size 1.27 1.27)
					)
					(hide yes)
				)
			)
			(property "MPN" "ESDA25P35-1U1M"
				(at 24.13 -7.62 0)
				(effects
					(font
						(size 1.27 1.27)
						(thickness 0.15)
					)
					(justify left bottom)
				)
			)
			(property "Manufacturer" "STMicroelectronics"
				(at 24.13 -17.78 0)
				(effects
					(font
						(size 1.27 1.27)
						(thickness 0.15)
					)
					(justify left bottom)
					(hide yes)
				)
			)
			(property "Author" "Antmicro"
				(at 24.13 -20.32 0)
				(effects
					(font
						(size 1.27 1.27)
						(thickness 0.15)
					)
					(justify left bottom)
					(hide yes)
				)
			)
			(property "License" "Apache-2.0"
				(at 24.13 -22.86 0)
				(effects
					(font
						(size 1.27 1.27)
						(thickness 0.15)
					)
					(justify left bottom)
					(hide yes)
				)
			)
			(property "ki_keywords" "DIODE, SEMICONDUCTOR, TVS, ESD"
				(at 0 0 0)
				(effects
					(font
						(size 1.27 1.27)
					)
					(hide yes)
				)
			)
			(symbol "ESDA25P35-1U1M_0_1"
				(polyline
					(pts
						(xy 1.905 0) (xy 0.635 0)
					)
					(stroke
						(width 0)
						(type default)
					)
					(fill
						(type none)
					)
				)
				(polyline
					(pts
						(xy 4.445 0) (xy 3.175 0)
					)
					(stroke
						(width 0)
						(type default)
					)
					(fill
						(type none)
					)
				)
			)
			(symbol "ESDA25P35-1U1M_1_1"
				(polyline
					(pts
						(xy 1.778 1.016) (xy 1.397 1.016)
					)
					(stroke
						(width 0.254)
						(type default)
					)
					(fill
						(type none)
					)
				)
				(polyline
					(pts
						(xy 1.778 1.016) (xy 1.778 -1.016)
					)
					(stroke
						(width 0.254)
						(type default)
					)
					(fill
						(type none)
					)
				)
				(polyline
					(pts
						(xy 2.159 -1.016) (xy 1.778 -1.016)
					)
					(stroke
						(width 0.254)
						(type default)
					)
					(fill
						(type none)
					)
				)
				(polyline
					(pts
						(xy 3.302 1.016) (xy 3.302 -1.016) (xy 1.778 0) (xy 3.302 1.016)
					)
					(stroke
						(width 0.254)
						(type default)
					)
					(fill
						(type outline)
					)
				)
				(pin passive line
					(at 0 0 0)
					(length 0.635)
					(name "C"
						(effects
							(font
								(size 1.27 1.27)
							)
						)
					)
					(number "1"
						(effects
							(font
								(size 1.27 1.27)
							)
						)
					)
				)
				(pin passive line
					(at 5.08 0 180)
					(length 0.635)
					(name "A"
						(effects
							(font
								(size 1.27 1.27)
							)
						)
					)
					(number "2"
						(effects
							(font
								(size 1.27 1.27)
							)
						)
					)
				)
			)
		)
	(symbol "antmicroTVSDiodes:SZSMF4L14AT3G"
			(pin_numbers
				(hide yes)
			)
			(pin_names
				(hide yes)
			)
			(exclude_from_sim no)
			(in_bom yes)
			(on_board yes)
			(property "Reference" "D"
				(at 15.24 -5.08 0)
				(effects
					(font
						(size 1.27 1.27)
						(thickness 0.15)
					)
					(justify left bottom)
				)
			)
			(property "Value" "SZSMF4L14AT3G"
				(at 15.24 -10.16 0)
				(effects
					(font
						(size 1.27 1.27)
						(thickness 0.15)
					)
					(justify left bottom)
					(hide yes)
				)
			)
			(property "Footprint" "antmicro-footprints:SOD-123FL"
				(at 15.24 -12.7 0)
				(effects
					(font
						(size 1.27 1.27)
						(thickness 0.15)
					)
					(justify left bottom)
					(hide yes)
				)
			)
			(property "Datasheet" "https://www.mouser.com/datasheet/2/240/media-3320461.pdf"
				(at 15.24 -15.24 0)
				(effects
					(font
						(size 1.27 1.27)
						(thickness 0.15)
					)
					(justify left bottom)
					(hide yes)
				)
			)
			(property "Description" "ESD, TVS Diode, 14V, UNI, 400W, SOD-123FL"
				(at 0 0 0)
				(effects
					(font
						(size 1.27 1.27)
					)
					(hide yes)
				)
			)
			(property "MPN" "SZSMF4L12AT3G"
				(at 15.24 -7.62 0)
				(effects
					(font
						(size 1.27 1.27)
						(thickness 0.15)
					)
					(justify left bottom)
				)
			)
			(property "Author" "Antmicro"
				(at 15.24 -17.78 0)
				(effects
					(font
						(size 1.27 1.27)
						(thickness 0.15)
					)
					(justify left bottom)
					(hide yes)
				)
			)
			(property "License" "Apache-2.0"
				(at 15.24 -20.32 0)
				(effects
					(font
						(size 1.27 1.27)
						(thickness 0.15)
					)
					(justify left bottom)
					(hide yes)
				)
			)
			(property "Manufacturer" "Littelfuse"
				(at 15.24 -22.86 0)
				(effects
					(font
						(size 1.27 1.27)
						(thickness 0.15)
					)
					(justify left bottom)
					(hide yes)
				)
			)
			(property "ki_keywords" "SMT, DIODE, SEMICONDUCTOR, ESD, TVS"
				(at 0 0 0)
				(effects
					(font
						(size 1.27 1.27)
					)
					(hide yes)
				)
			)
			(symbol "SZSMF4L14AT3G_0_1"
				(polyline
					(pts
						(xy 1.905 0) (xy 0.635 0)
					)
					(stroke
						(width 0)
						(type default)
					)
					(fill
						(type none)
					)
				)
				(polyline
					(pts
						(xy 4.445 0) (xy 3.175 0)
					)
					(stroke
						(width 0)
						(type default)
					)
					(fill
						(type none)
					)
				)
			)
			(symbol "SZSMF4L14AT3G_1_1"
				(polyline
					(pts
						(xy 1.778 1.016) (xy 1.397 1.016)
					)
					(stroke
						(width 0.254)
						(type default)
					)
					(fill
						(type none)
					)
				)
				(polyline
					(pts
						(xy 1.778 1.016) (xy 1.778 -1.016)
					)
					(stroke
						(width 0.254)
						(type default)
					)
					(fill
						(type none)
					)
				)
				(polyline
					(pts
						(xy 2.159 -1.016) (xy 1.778 -1.016)
					)
					(stroke
						(width 0.254)
						(type default)
					)
					(fill
						(type none)
					)
				)
				(polyline
					(pts
						(xy 3.302 1.016) (xy 3.302 -1.016) (xy 1.778 0) (xy 3.302 1.016)
					)
					(stroke
						(width 0.254)
						(type default)
					)
					(fill
						(type outline)
					)
				)
				(pin passive line
					(at 0 0 0)
					(length 0.635)
					(name "C"
						(effects
							(font
								(size 1.27 1.27)
							)
						)
					)
					(number "1"
						(effects
							(font
								(size 1.27 1.27)
							)
						)
					)
				)
				(pin passive line
					(at 5.08 0 180)
					(length 0.635)
					(name "A"
						(effects
							(font
								(size 1.27 1.27)
							)
						)
					)
					(number "2"
						(effects
							(font
								(size 1.27 1.27)
							)
						)
					)
				)
			)
		)
	(symbol "antmicroTVSDiodes:TPD2E2U06_SC70"
			(pin_names
				(hide yes)
			)
			(exclude_from_sim no)
			(in_bom yes)
			(on_board yes)
			(property "Reference" "D"
				(at 12.7 2.54 0)
				(effects
					(font
						(size 1.27 1.27)
						(thickness 0.15)
					)
					(justify left bottom)
				)
			)
			(property "Value" "TPD2E2U06_SC70"
				(at 12.7 -2.54 0)
				(effects
					(font
						(size 1.27 1.27)
						(thickness 0.15)
					)
					(justify left bottom)
					(hide yes)
				)
			)
			(property "Footprint" "antmicro-footprints:SC70-3"
				(at 12.7 -5.08 0)
				(effects
					(font
						(size 1.27 1.27)
						(thickness 0.15)
					)
					(justify left bottom)
					(hide yes)
				)
			)
			(property "Datasheet" "https://www.ti.com/lit/ds/symlink/tpd2e2u06.pdf?ts=1706006131823&ref_url=https%253A%252F%252Fwww.ti.com%252Finterface%252Fdiodes%252Fesd-protection-diodes%252Fproducts.html"
				(at 12.7 -7.62 0)
				(effects
					(font
						(size 1.27 1.27)
						(thickness 0.15)
					)
					(justify left bottom)
					(hide yes)
				)
			)
			(property "Description" "TVS diode array, 15 kV, SC70, 5.5V, 1.5 pF"
				(at 0 0 0)
				(effects
					(font
						(size 1.27 1.27)
					)
					(hide yes)
				)
			)
			(property "MPN" "TPD2E2U06DCKR"
				(at 12.7 0 0)
				(effects
					(font
						(size 1.27 1.27)
						(thickness 0.15)
					)
					(justify left bottom)
				)
			)
			(property "Manufacturer" "Texas Instruments"
				(at 12.7 -10.16 0)
				(effects
					(font
						(size 1.27 1.27)
						(thickness 0.15)
					)
					(justify left bottom)
					(hide yes)
				)
			)
			(property "Author" "Antmicro"
				(at 12.7 -12.7 0)
				(effects
					(font
						(size 1.27 1.27)
						(thickness 0.15)
					)
					(justify left bottom)
					(hide yes)
				)
			)
			(property "License" "Apache-2.0"
				(at 12.7 -15.24 0)
				(effects
					(font
						(size 1.27 1.27)
						(thickness 0.15)
					)
					(justify left bottom)
					(hide yes)
				)
			)
			(property "ki_keywords" "SMT, DIODE, SEMICONDUCTOR, TVS, ESD"
				(at 0 0 0)
				(effects
					(font
						(size 1.27 1.27)
					)
					(hide yes)
				)
			)
			(symbol "TPD2E2U06_SC70_0_1"
				(polyline
					(pts
						(xy 2.54 -5.08) (xy 6.35 -5.08) (xy 6.35 0) (xy 5.08 0)
					)
					(stroke
						(width 0.254)
						(type default)
					)
					(fill
						(type none)
					)
				)
				(polyline
					(pts
						(xy 3.81 0) (xy 2.54 0)
					)
					(stroke
						(width 0.254)
						(type default)
					)
					(fill
						(type none)
					)
				)
				(polyline
					(pts
						(xy 3.81 -2.54) (xy 2.54 -2.54)
					)
					(stroke
						(width 0.254)
						(type default)
					)
					(fill
						(type none)
					)
				)
				(polyline
					(pts
						(xy 5.08 -2.54) (xy 6.35 -2.54)
					)
					(stroke
						(width 0.254)
						(type default)
					)
					(fill
						(type none)
					)
				)
			)
			(symbol "TPD2E2U06_SC70_1_1"
				(rectangle
					(start 2.54 2.54)
					(end 7.62 -7.62)
					(stroke
						(width 0.254)
						(type default)
					)
					(fill
						(type background)
					)
				)
				(polyline
					(pts
						(xy 3.81 -0.635) (xy 3.81 -0.381) (xy 3.81 0.381) (xy 4.064 0.635)
					)
					(stroke
						(width 0.254)
						(type default)
					)
					(fill
						(type background)
					)
				)
				(polyline
					(pts
						(xy 3.81 -3.175) (xy 3.81 -2.921) (xy 3.81 -2.159) (xy 4.064 -1.905)
					)
					(stroke
						(width 0.254)
						(type default)
					)
					(fill
						(type background)
					)
				)
				(polyline
					(pts
						(xy 5.08 -0.635) (xy 5.08 0.635) (xy 3.81 0) (xy 5.08 -0.635)
					)
					(stroke
						(width 0.254)
						(type default)
					)
					(fill
						(type outline)
					)
				)
				(polyline
					(pts
						(xy 5.08 -3.175) (xy 5.08 -1.905) (xy 3.81 -2.54) (xy 5.08 -3.175)
					)
					(stroke
						(width 0.254)
						(type default)
					)
					(fill
						(type outline)
					)
				)
				(circle
					(center 6.35 -2.54)
					(radius 0.127)
					(stroke
						(width 0.254)
						(type default)
					)
					(fill
						(type background)
					)
				)
				(pin passive line
					(at 0 0 0)
					(length 2.54)
					(name "1"
						(effects
							(font
								(size 1.27 1.27)
							)
						)
					)
					(number "1"
						(effects
							(font
								(size 1.27 1.27)
							)
						)
					)
				)
				(pin passive line
					(at 0 -2.54 0)
					(length 2.54)
					(name "2"
						(effects
							(font
								(size 1.27 1.27)
							)
						)
					)
					(number "2"
						(effects
							(font
								(size 1.27 1.27)
							)
						)
					)
				)
				(pin passive line
					(at 0 -5.08 0)
					(length 2.54)
					(name "3"
						(effects
							(font
								(size 1.27 1.27)
							)
						)
					)
					(number "3"
						(effects
							(font
								(size 1.27 1.27)
							)
						)
					)
				)
			)
		)
	(symbol "antmicroTestPoints:TP_Pad0.75mm_Drill0.2mm"
			(pin_names
				(hide yes)
			)
			(exclude_from_sim no)
			(in_bom no)
			(on_board yes)
			(property "Reference" "TP"
				(at 10.16 -1.27 0)
				(effects
					(font
						(size 1.27 1.27)
						(thickness 0.15)
					)
					(justify left bottom)
				)
			)
			(property "Value" "TP_Pad0.75mm_Drill0.2mm"
				(at 10.16 -3.81 0)
				(effects
					(font
						(size 1.27 1.27)
						(thickness 0.15)
					)
					(justify left bottom)
					(hide yes)
				)
			)
			(property "Footprint" "antmicro-footprints:TP_Pad0.75mm_Drill0.2mm"
				(at 10.16 -6.35 0)
				(effects
					(font
						(size 1.27 1.27)
						(thickness 0.15)
					)
					(justify left bottom)
					(hide yes)
				)
			)
			(property "Datasheet" ""
				(at 17.78 -12.7 0)
				(effects
					(font
						(size 1.27 1.27)
						(thickness 0.15)
					)
					(justify left bottom)
					(hide yes)
				)
			)
			(property "Description" "SMT test point"
				(at 0 0 0)
				(effects
					(font
						(size 1.27 1.27)
					)
					(hide yes)
				)
			)
			(property "MPN" ""
				(at 10.795 -11.43 0)
				(effects
					(font
						(size 1.27 1.27)
						(thickness 0.15)
					)
					(justify left bottom)
					(hide yes)
				)
			)
			(property "Manufacturer" ""
				(at 10.795 -6.35 0)
				(effects
					(font
						(size 1.27 1.27)
						(thickness 0.15)
					)
					(justify left bottom)
					(hide yes)
				)
			)
			(property "Author" "Antmicro"
				(at 10.16 -8.89 0)
				(effects
					(font
						(size 1.27 1.27)
						(thickness 0.15)
					)
					(justify left bottom)
					(hide yes)
				)
			)
			(property "License" "Apache-2.0"
				(at 10.16 -11.43 0)
				(effects
					(font
						(size 1.27 1.27)
						(thickness 0.15)
					)
					(justify left bottom)
					(hide yes)
				)
			)
			(property "ki_keywords" "TESTPOINT"
				(at 0 0 0)
				(effects
					(font
						(size 1.27 1.27)
					)
					(hide yes)
				)
			)
			(symbol "TP_Pad0.75mm_Drill0.2mm_1_1"
				(circle
					(center 3.175 0)
					(radius 0.635)
					(stroke
						(width 0.254)
						(type default)
					)
					(fill
						(type none)
					)
				)
				(pin passive line
					(at 0 0 0)
					(length 2.54)
					(name "1"
						(effects
							(font
								(size 1.27 1.27)
							)
						)
					)
					(number "1"
						(effects
							(font
								(size 1.27 1.27)
							)
						)
					)
				)
			)
		)
	(symbol "antmicroTransistorsFETsMOSFETsSingle:BSS138-7-F"
			(pin_names
				(offset 0)
			)
			(exclude_from_sim no)
			(in_bom yes)
			(on_board yes)
			(property "Reference" "Q"
				(at 22.86 -2.54 0)
				(effects
					(font
						(size 1.27 1.27)
						(thickness 0.15)
					)
					(justify left bottom)
				)
			)
			(property "Value" "BSS138-7-F"
				(at 22.86 -5.08 0)
				(effects
					(font
						(size 1.27 1.27)
						(thickness 0.15)
					)
					(justify left bottom)
					(hide yes)
				)
			)
			(property "Footprint" "antmicro-footprints:SOT-23-3"
				(at 22.86 -7.62 0)
				(effects
					(font
						(size 1.27 1.27)
						(thickness 0.15)
					)
					(justify left bottom)
					(hide yes)
				)
			)
			(property "Datasheet" "https://www.diodes.com/assets/Datasheets/ds30144.pdf"
				(at 22.86 -10.16 0)
				(effects
					(font
						(size 1.27 1.27)
						(thickness 0.15)
					)
					(justify left bottom)
					(hide yes)
				)
			)
			(property "Description" "Power MOSFET, N Channel, 50 V, 200 mA, 1.4 ohm, SOT-23, Surface Mount"
				(at 59.944 -21.844 0)
				(effects
					(font
						(size 1.27 1.27)
					)
					(hide yes)
				)
			)
			(property "MPN" "BSS138-7-F"
				(at 22.86 -12.7 0)
				(effects
					(font
						(size 1.27 1.27)
						(thickness 0.15)
					)
					(justify left bottom)
				)
			)
			(property "Manufacturer" "Diodes Incorporated"
				(at 22.86 -15.24 0)
				(effects
					(font
						(size 1.27 1.27)
						(thickness 0.15)
					)
					(justify left bottom)
					(hide yes)
				)
			)
			(property "Author" "Antmicro"
				(at 22.86 -17.78 0)
				(effects
					(font
						(size 1.27 1.27)
						(thickness 0.15)
					)
					(justify left bottom)
					(hide yes)
				)
			)
			(property "License" "Apache-2.0"
				(at 22.86 -20.32 0)
				(effects
					(font
						(size 1.27 1.27)
						(thickness 0.15)
					)
					(justify left bottom)
					(hide yes)
				)
			)
			(property "ki_keywords" "SMT, MOSFET, SEMICONDUCTOR"
				(at 0 0 0)
				(effects
					(font
						(size 1.27 1.27)
					)
					(hide yes)
				)
			)
			(symbol "BSS138-7-F_1_1"
				(polyline
					(pts
						(xy 2.54 0) (xy 4.572 0) (xy 4.572 3.937)
					)
					(stroke
						(width 0.254)
						(type default)
					)
					(fill
						(type none)
					)
				)
				(polyline
					(pts
						(xy 5.08 4.445) (xy 5.08 3.429)
					)
					(stroke
						(width 0.254)
						(type default)
					)
					(fill
						(type background)
					)
				)
				(polyline
					(pts
						(xy 5.08 2.54) (xy 5.08 3.048)
					)
					(stroke
						(width 0.254)
						(type default)
					)
					(fill
						(type background)
					)
				)
				(polyline
					(pts
						(xy 5.08 2.54) (xy 5.08 2.032)
					)
					(stroke
						(width 0.254)
						(type default)
					)
					(fill
						(type background)
					)
				)
				(polyline
					(pts
						(xy 5.08 2.54) (xy 5.842 3.048) (xy 5.842 2.032) (xy 5.08 2.54)
					)
					(stroke
						(width 0.254)
						(type default)
					)
					(fill
						(type outline)
					)
				)
				(polyline
					(pts
						(xy 5.08 1.143) (xy 5.08 1.651)
					)
					(stroke
						(width 0.254)
						(type default)
					)
					(fill
						(type background)
					)
				)
				(polyline
					(pts
						(xy 5.08 1.143) (xy 5.08 0.635)
					)
					(stroke
						(width 0.254)
						(type default)
					)
					(fill
						(type background)
					)
				)
				(circle
					(center 6.35 2.54)
					(radius 3.302)
					(stroke
						(width 0.254)
						(type default)
					)
					(fill
						(type background)
					)
				)
				(polyline
					(pts
						(xy 7.493 0.635) (xy 8.636 0.635) (xy 8.636 3.937) (xy 8.636 4.445) (xy 7.493 4.445)
					)
					(stroke
						(width 0.254)
						(type default)
					)
					(fill
						(type background)
					)
				)
				(polyline
					(pts
						(xy 7.62 6.35) (xy 7.62 3.937) (xy 5.08 3.937)
					)
					(stroke
						(width 0.254)
						(type default)
					)
					(fill
						(type none)
					)
				)
				(circle
					(center 7.62 4.445)
					(radius 0.127)
					(stroke
						(width 0.254)
						(type default)
					)
					(fill
						(type background)
					)
				)
				(polyline
					(pts
						(xy 7.62 1.143) (xy 5.08 1.143)
					)
					(stroke
						(width 0.254)
						(type default)
					)
					(fill
						(type background)
					)
				)
				(circle
					(center 7.62 1.143)
					(radius 0.127)
					(stroke
						(width 0.254)
						(type default)
					)
					(fill
						(type background)
					)
				)
				(circle
					(center 7.62 0.635)
					(radius 0.127)
					(stroke
						(width 0.254)
						(type default)
					)
					(fill
						(type background)
					)
				)
				(polyline
					(pts
						(xy 7.62 -1.27) (xy 7.62 2.54) (xy 5.08 2.54)
					)
					(stroke
						(width 0.254)
						(type default)
					)
					(fill
						(type none)
					)
				)
				(polyline
					(pts
						(xy 8.636 3.048) (xy 8.128 2.286) (xy 9.144 2.286) (xy 8.636 3.048)
					)
					(stroke
						(width 0.254)
						(type default)
					)
					(fill
						(type outline)
					)
				)
				(polyline
					(pts
						(xy 9.144 3.048) (xy 8.128 3.048)
					)
					(stroke
						(width 0.254)
						(type default)
					)
					(fill
						(type background)
					)
				)
				(pin input line
					(at 0 0 0)
					(length 2.54)
					(name "G"
						(effects
							(font
								(size 1.27 1.27)
							)
						)
					)
					(number "1"
						(effects
							(font
								(size 1.27 1.27)
							)
						)
					)
				)
				(pin passive line
					(at 7.62 8.89 270)
					(length 2.54)
					(name "D"
						(effects
							(font
								(size 1.27 1.27)
							)
						)
					)
					(number "3"
						(effects
							(font
								(size 1.27 1.27)
							)
						)
					)
				)
				(pin passive line
					(at 7.62 -3.81 90)
					(length 2.54)
					(name "S"
						(effects
							(font
								(size 1.27 1.27)
							)
						)
					)
					(number "2"
						(effects
							(font
								(size 1.27 1.27)
							)
						)
					)
				)
			)
		)
	(symbol "antmicroTransistorsFETsMOSFETsSingle:SQS401EN-T1_BE3"
			(pin_names
				(offset 0)
			)
			(exclude_from_sim no)
			(in_bom no)
			(on_board yes)
			(property "Reference" "Q"
				(at 15.24 -5.08 0)
				(effects
					(font
						(size 1.27 1.27)
						(thickness 0.15)
					)
					(justify left bottom)
				)
			)
			(property "Value" "SQS401EN-T1_BE3"
				(at 15.24 -10.16 0)
				(effects
					(font
						(size 1.27 1.27)
						(thickness 0.15)
					)
					(justify left bottom)
					(hide yes)
				)
			)
			(property "Footprint" "antmicro-footprints:Vishay_PowerPAK_1212-8_Single"
				(at 15.24 -12.7 0)
				(effects
					(font
						(size 1.27 1.27)
						(thickness 0.15)
					)
					(justify left bottom)
					(hide yes)
				)
			)
			(property "Datasheet" "https://www.vishay.com/docs/65529/sqs401en.pdf"
				(at 15.24 -15.24 0)
				(effects
					(font
						(size 1.27 1.27)
						(thickness 0.15)
					)
					(justify left bottom)
					(hide yes)
				)
			)
			(property "Description" "MOSFET, P Channel, 40 V, 16A, 0.047 ohm, PowerPAK 1212-8, Surface Mount"
				(at 53.34 -24.384 0)
				(effects
					(font
						(size 1.27 1.27)
					)
					(hide yes)
				)
			)
			(property "MPN" "SQS401EN-T1_BE3"
				(at 15.24 -7.62 0)
				(effects
					(font
						(size 1.27 1.27)
						(thickness 0.15)
					)
					(justify left bottom)
				)
			)
			(property "Manufacturer" "Vishay"
				(at 15.24 -17.78 0)
				(effects
					(font
						(size 1.27 1.27)
						(thickness 0.15)
					)
					(justify left bottom)
					(hide yes)
				)
			)
			(property "Author" "Antmicro"
				(at 15.24 -20.32 0)
				(effects
					(font
						(size 1.27 1.27)
						(thickness 0.15)
					)
					(justify left bottom)
					(hide yes)
				)
			)
			(property "License" "Apache-2.0"
				(at 15.24 -22.86 0)
				(effects
					(font
						(size 1.27 1.27)
						(thickness 0.15)
					)
					(justify left bottom)
					(hide yes)
				)
			)
			(property "ki_keywords" "SMT, TRANSISTOR, SEMICONDUCTOR, MOSFET, PMOS"
				(at 0 0 0)
				(effects
					(font
						(size 1.27 1.27)
					)
					(hide yes)
				)
			)
			(symbol "SQS401EN-T1_BE3_1_1"
				(polyline
					(pts
						(xy 1.27 0) (xy 3.302 0) (xy 3.302 3.937)
					)
					(stroke
						(width 0.254)
						(type default)
					)
					(fill
						(type none)
					)
				)
				(polyline
					(pts
						(xy 3.81 4.445) (xy 3.81 3.429)
					)
					(stroke
						(width 0.254)
						(type default)
					)
					(fill
						(type background)
					)
				)
				(polyline
					(pts
						(xy 3.81 2.54) (xy 3.81 3.048)
					)
					(stroke
						(width 0.254)
						(type default)
					)
					(fill
						(type background)
					)
				)
				(polyline
					(pts
						(xy 3.81 2.54) (xy 3.81 2.032)
					)
					(stroke
						(width 0.254)
						(type default)
					)
					(fill
						(type background)
					)
				)
				(polyline
					(pts
						(xy 3.81 1.143) (xy 3.81 1.651)
					)
					(stroke
						(width 0.254)
						(type default)
					)
					(fill
						(type background)
					)
				)
				(polyline
					(pts
						(xy 3.81 1.143) (xy 3.81 0.635)
					)
					(stroke
						(width 0.254)
						(type default)
					)
					(fill
						(type background)
					)
				)
				(circle
					(center 5.08 2.54)
					(radius 3.302)
					(stroke
						(width 0.254)
						(type default)
					)
					(fill
						(type background)
					)
				)
				(polyline
					(pts
						(xy 6.096 2.54) (xy 5.334 2.032) (xy 5.334 3.048) (xy 6.096 2.54)
					)
					(stroke
						(width 0.254)
						(type default)
					)
					(fill
						(type outline)
					)
				)
				(polyline
					(pts
						(xy 6.223 0.635) (xy 7.366 0.635) (xy 7.366 3.937) (xy 7.366 4.445) (xy 6.223 4.445)
					)
					(stroke
						(width 0.254)
						(type default)
					)
					(fill
						(type none)
					)
				)
				(polyline
					(pts
						(xy 6.35 6.35) (xy 6.35 3.937) (xy 3.81 3.937)
					)
					(stroke
						(width 0.254)
						(type default)
					)
					(fill
						(type none)
					)
				)
				(circle
					(center 6.35 4.445)
					(radius 0.127)
					(stroke
						(width 0.254)
						(type default)
					)
					(fill
						(type background)
					)
				)
				(polyline
					(pts
						(xy 6.35 1.143) (xy 3.81 1.143)
					)
					(stroke
						(width 0.254)
						(type default)
					)
					(fill
						(type background)
					)
				)
				(circle
					(center 6.35 1.143)
					(radius 0.127)
					(stroke
						(width 0.254)
						(type default)
					)
					(fill
						(type background)
					)
				)
				(circle
					(center 6.35 0.635)
					(radius 0.127)
					(stroke
						(width 0.254)
						(type default)
					)
					(fill
						(type background)
					)
				)
				(polyline
					(pts
						(xy 6.35 -1.27) (xy 6.35 2.54) (xy 3.81 2.54)
					)
					(stroke
						(width 0.254)
						(type default)
					)
					(fill
						(type none)
					)
				)
				(polyline
					(pts
						(xy 7.366 2.286) (xy 7.874 3.048) (xy 6.858 3.048) (xy 7.366 2.286)
					)
					(stroke
						(width 0.254)
						(type default)
					)
					(fill
						(type outline)
					)
				)
				(polyline
					(pts
						(xy 7.874 2.286) (xy 6.858 2.286)
					)
					(stroke
						(width 0.254)
						(type default)
					)
					(fill
						(type background)
					)
				)
				(pin input line
					(at 0 0 0)
					(length 2.54)
					(name "G"
						(effects
							(font
								(size 1.27 1.27)
							)
						)
					)
					(number "4"
						(effects
							(font
								(size 1.27 1.27)
							)
						)
					)
				)
				(pin passive line
					(at 6.35 7.62 270)
					(length 2.54)
					(name "D"
						(effects
							(font
								(size 1.27 1.27)
							)
						)
					)
					(number "5"
						(effects
							(font
								(size 1.27 1.27)
							)
						)
					)
				)
				(pin passive line
					(at 6.35 -2.54 90)
					(length 2.54)
					(name "S"
						(effects
							(font
								(size 1.27 1.27)
							)
						)
					)
					(number "1"
						(effects
							(font
								(size 1.27 1.27)
							)
						)
					)
				)
				(pin passive line
					(at 6.35 -2.54 90)
					(length 2.54)
					(hide yes)
					(name "S"
						(effects
							(font
								(size 1.27 1.27)
							)
						)
					)
					(number "2"
						(effects
							(font
								(size 1.27 1.27)
							)
						)
					)
				)
				(pin passive line
					(at 6.35 -2.54 90)
					(length 2.54)
					(hide yes)
					(name "S"
						(effects
							(font
								(size 1.27 1.27)
							)
						)
					)
					(number "3"
						(effects
							(font
								(size 1.27 1.27)
							)
						)
					)
				)
			)
		)
	(symbol "antmicroUSBConnectors:USB-C_GCT_USB4105-GF-A"
			(exclude_from_sim no)
			(in_bom yes)
			(on_board yes)
			(property "Reference" "J"
				(at 38.1 -2.54 0)
				(effects
					(font
						(size 1.27 1.27)
						(thickness 0.15)
					)
					(justify left bottom)
				)
			)
			(property "Value" "USB-C_GCT_USB4105-GF-A"
				(at 38.1 -5.08 0)
				(effects
					(font
						(size 1.27 1.27)
						(thickness 0.15)
					)
					(justify left bottom)
				)
			)
			(property "Footprint" "antmicro-footprints:USB-C_Receptacle_GCT_USB4105-GF-A"
				(at 38.1 -7.62 0)
				(effects
					(font
						(size 1.27 1.27)
						(thickness 0.15)
					)
					(justify left bottom)
					(hide yes)
				)
			)
			(property "Datasheet" "https://gct.co/files/drawings/usb4105.pdf"
				(at 38.1 -10.16 0)
				(effects
					(font
						(size 1.27 1.27)
						(thickness 0.15)
					)
					(justify left bottom)
					(hide yes)
				)
			)
			(property "Description" "USB-C (USB TYPE-C) USB 2.0 Receptacle Connector 24 (16+8 Dummy) Position Surface Mount, Right Angle"
				(at 0 0 0)
				(effects
					(font
						(size 1.27 1.27)
					)
					(hide yes)
				)
			)
			(property "Manufacturer" "GCT"
				(at 38.1 -12.7 0)
				(effects
					(font
						(size 1.27 1.27)
						(thickness 0.15)
					)
					(justify left bottom)
					(hide yes)
				)
			)
			(property "MPN" "USB4105-GF-A"
				(at 38.1 -15.24 0)
				(effects
					(font
						(size 1.27 1.27)
						(thickness 0.15)
					)
					(justify left bottom)
					(hide yes)
				)
			)
			(property "Author" "Antmicro"
				(at 38.1 -17.78 0)
				(effects
					(font
						(size 1.27 1.27)
						(thickness 0.15)
					)
					(justify left bottom)
					(hide yes)
				)
			)
			(property "License" "Apache-2.0"
				(at 38.1 -20.32 0)
				(effects
					(font
						(size 1.27 1.27)
						(thickness 0.15)
					)
					(justify left bottom)
					(hide yes)
				)
			)
			(property "ki_keywords" "USB, CONNECTOR, SMT, HORIZONTAL"
				(at 0 0 0)
				(effects
					(font
						(size 1.27 1.27)
					)
					(hide yes)
				)
			)
			(symbol "USB-C_GCT_USB4105-GF-A_1_1"
				(rectangle
					(start -22.86 2.54)
					(end -3.81 -38.1)
					(stroke
						(width 0.254)
						(type default)
					)
					(fill
						(type background)
					)
				)
				(circle
					(center -20.066 -18.034)
					(radius 0.284)
					(stroke
						(width 0.254)
						(type default)
					)
					(fill
						(type outline)
					)
				)
				(polyline
					(pts
						(xy -19.812 -16.383) (xy -19.177 -15.24) (xy -18.542 -16.383) (xy -19.812 -16.383)
					)
					(stroke
						(width 0.254)
						(type default)
					)
					(fill
						(type outline)
					)
				)
				(polyline
					(pts
						(xy -19.177 -19.558) (xy -18.288 -18.669) (xy -18.288 -18.034)
					)
					(stroke
						(width 0.254)
						(type default)
					)
					(fill
						(type background)
					)
				)
				(polyline
					(pts
						(xy -19.177 -19.939) (xy -20.066 -19.05) (xy -20.066 -18.415)
					)
					(stroke
						(width 0.254)
						(type default)
					)
					(fill
						(type background)
					)
				)
				(polyline
					(pts
						(xy -19.177 -20.701) (xy -19.177 -16.383)
					)
					(stroke
						(width 0.254)
						(type default)
					)
					(fill
						(type background)
					)
				)
				(circle
					(center -19.177 -20.828)
					(radius 0.5236)
					(stroke
						(width 0.254)
						(type default)
					)
					(fill
						(type outline)
					)
				)
				(rectangle
					(start -18.669 -18.034)
					(end -17.907 -17.272)
					(stroke
						(width 0.254)
						(type default)
					)
					(fill
						(type outline)
					)
				)
				(polyline
					(pts
						(xy -16.51 -21.59) (xy -16.51 -13.97)
					)
					(stroke
						(width 0.254)
						(type default)
					)
					(fill
						(type background)
					)
				)
				(rectangle
					(start -15.24 -21.59)
					(end -13.97 -13.97)
					(stroke
						(width 0.254)
						(type default)
					)
					(fill
						(type outline)
					)
				)
				(arc
					(start -15.24 -13.97)
					(mid -14.605 -13.3377)
					(end -13.97 -13.97)
					(stroke
						(width 0.254)
						(type default)
					)
					(fill
						(type outline)
					)
				)
				(arc
					(start -15.24 -13.97)
					(mid -14.605 -13.3377)
					(end -13.97 -13.97)
					(stroke
						(width 0.254)
						(type default)
					)
					(fill
						(type background)
					)
				)
				(arc
					(start -16.51 -13.97)
					(mid -14.605 -12.0733)
					(end -12.7 -13.97)
					(stroke
						(width 0.254)
						(type default)
					)
					(fill
						(type background)
					)
				)
				(arc
					(start -12.7 -21.59)
					(mid -14.605 -23.4867)
					(end -16.51 -21.59)
					(stroke
						(width 0.254)
						(type default)
					)
					(fill
						(type background)
					)
				)
				(arc
					(start -13.97 -21.59)
					(mid -14.605 -22.2223)
					(end -15.24 -21.59)
					(stroke
						(width 0.254)
						(type default)
					)
					(fill
						(type outline)
					)
				)
				(arc
					(start -13.97 -21.59)
					(mid -14.605 -22.2223)
					(end -15.24 -21.59)
					(stroke
						(width 0.254)
						(type default)
					)
					(fill
						(type background)
					)
				)
				(polyline
					(pts
						(xy -12.7 -13.97) (xy -12.7 -21.59)
					)
					(stroke
						(width 0.254)
						(type default)
					)
					(fill
						(type background)
					)
				)
				(pin passive line
					(at 0 0 180)
					(length 3.81)
					(name "VBUS"
						(effects
							(font
								(size 1.27 1.27)
							)
						)
					)
					(number "A4"
						(effects
							(font
								(size 1.27 1.27)
							)
						)
					)
				)
				(pin passive line
					(at 0 0 180)
					(length 3.81)
					(hide yes)
					(name "VBUS"
						(effects
							(font
								(size 1.27 1.27)
							)
						)
					)
					(number "A9"
						(effects
							(font
								(size 1.27 1.27)
							)
						)
					)
				)
				(pin passive line
					(at 0 0 180)
					(length 3.81)
					(hide yes)
					(name "VBUS"
						(effects
							(font
								(size 1.27 1.27)
							)
						)
					)
					(number "B4"
						(effects
							(font
								(size 1.27 1.27)
							)
						)
					)
				)
				(pin passive line
					(at 0 0 180)
					(length 3.81)
					(hide yes)
					(name "VBUS"
						(effects
							(font
								(size 1.27 1.27)
							)
						)
					)
					(number "B9"
						(effects
							(font
								(size 1.27 1.27)
							)
						)
					)
				)
				(pin bidirectional line
					(at 0 -5.08 180)
					(length 3.81)
					(name "CC_{1}"
						(effects
							(font
								(size 1.27 1.27)
							)
						)
					)
					(number "A5"
						(effects
							(font
								(size 1.27 1.27)
							)
						)
					)
				)
				(pin bidirectional line
					(at 0 -7.62 180)
					(length 3.81)
					(name "CC_{2}"
						(effects
							(font
								(size 1.27 1.27)
							)
						)
					)
					(number "B5"
						(effects
							(font
								(size 1.27 1.27)
							)
						)
					)
				)
				(pin bidirectional line
					(at 0 -12.7 180)
					(length 3.81)
					(name "D_{A}+"
						(effects
							(font
								(size 1.27 1.27)
							)
						)
					)
					(number "A6"
						(effects
							(font
								(size 1.27 1.27)
							)
						)
					)
				)
				(pin bidirectional line
					(at 0 -15.24 180)
					(length 3.81)
					(name "D_{A}-"
						(effects
							(font
								(size 1.27 1.27)
							)
						)
					)
					(number "A7"
						(effects
							(font
								(size 1.27 1.27)
							)
						)
					)
				)
				(pin bidirectional line
					(at 0 -17.78 180)
					(length 3.81)
					(name "D_{B}+"
						(effects
							(font
								(size 1.27 1.27)
							)
						)
					)
					(number "B6"
						(effects
							(font
								(size 1.27 1.27)
							)
						)
					)
				)
				(pin bidirectional line
					(at 0 -20.32 180)
					(length 3.81)
					(name "D_{B}-"
						(effects
							(font
								(size 1.27 1.27)
							)
						)
					)
					(number "B7"
						(effects
							(font
								(size 1.27 1.27)
							)
						)
					)
				)
				(pin bidirectional line
					(at 0 -25.4 180)
					(length 3.81)
					(name "SBU_{1}"
						(effects
							(font
								(size 1.27 1.27)
							)
						)
					)
					(number "A8"
						(effects
							(font
								(size 1.27 1.27)
							)
						)
					)
				)
				(pin bidirectional line
					(at 0 -27.94 180)
					(length 3.81)
					(name "SBU_{2}"
						(effects
							(font
								(size 1.27 1.27)
							)
						)
					)
					(number "B8"
						(effects
							(font
								(size 1.27 1.27)
							)
						)
					)
				)
				(pin power_in line
					(at 0 -33.02 180)
					(length 3.81)
					(name "GND"
						(effects
							(font
								(size 1.27 1.27)
							)
						)
					)
					(number "A1"
						(effects
							(font
								(size 1.27 1.27)
							)
						)
					)
				)
				(pin passive line
					(at 0 -33.02 180)
					(length 3.81)
					(hide yes)
					(name "GND"
						(effects
							(font
								(size 1.27 1.27)
							)
						)
					)
					(number "A12"
						(effects
							(font
								(size 1.27 1.27)
							)
						)
					)
				)
				(pin passive line
					(at 0 -33.02 180)
					(length 3.81)
					(hide yes)
					(name "GND"
						(effects
							(font
								(size 1.27 1.27)
							)
						)
					)
					(number "B1"
						(effects
							(font
								(size 1.27 1.27)
							)
						)
					)
				)
				(pin passive line
					(at 0 -33.02 180)
					(length 3.81)
					(hide yes)
					(name "GND"
						(effects
							(font
								(size 1.27 1.27)
							)
						)
					)
					(number "B12"
						(effects
							(font
								(size 1.27 1.27)
							)
						)
					)
				)
				(pin passive line
					(at 0 -35.56 180)
					(length 3.81)
					(name "SH"
						(effects
							(font
								(size 1.27 1.27)
							)
						)
					)
					(number "SH"
						(effects
							(font
								(size 1.27 1.27)
							)
						)
					)
				)
			)
		)
	(symbol "antmicroWire2BoardConnectors:Molex_Mini-Fit-Jr_2x4_39-28-8080"
			(exclude_from_sim no)
			(in_bom yes)
			(on_board yes)
			(property "Reference" "J"
				(at 26.67 -3.81 0)
				(effects
					(font
						(size 1.27 1.27)
						(thickness 0.15)
					)
					(justify left bottom)
				)
			)
			(property "Value" "Molex_Mini-Fit-Jr_2x4_39-28-8080"
				(at 26.67 -8.89 0)
				(effects
					(font
						(size 1.27 1.27)
						(thickness 0.15)
					)
					(justify left bottom)
					(hide yes)
				)
			)
			(property "Footprint" "antmicro-footprints:MOLEX_39288080"
				(at 26.67 -11.43 0)
				(effects
					(font
						(size 1.27 1.27)
						(thickness 0.15)
					)
					(justify left bottom)
					(hide yes)
				)
			)
			(property "Datasheet" "https://www.molex.com/pdm_docs/sd/039288080_sd.pdf"
				(at 26.67 -13.97 0)
				(effects
					(font
						(size 1.27 1.27)
						(thickness 0.15)
					)
					(justify left bottom)
					(hide yes)
				)
			)
			(property "Description" "Pin Header, THT, Vertical, UL94V-2, Power, Wire-to-Board, 4.2 mm, 2 Rows, 8 Contacts, Mini-fit Jr, 5566 series"
				(at 0 0 0)
				(effects
					(font
						(size 1.27 1.27)
					)
					(hide yes)
				)
			)
			(property "MPN" "39-28-8080"
				(at 26.67 -6.35 0)
				(effects
					(font
						(size 1.27 1.27)
						(thickness 0.15)
					)
					(justify left bottom)
				)
			)
			(property "Manufacturer" "Molex"
				(at 26.67 -16.51 0)
				(effects
					(font
						(size 1.27 1.27)
						(thickness 0.15)
					)
					(justify left bottom)
					(hide yes)
				)
			)
			(property "Author" "Antmicro"
				(at 26.67 -19.05 0)
				(effects
					(font
						(size 1.27 1.27)
						(thickness 0.15)
					)
					(justify left bottom)
					(hide yes)
				)
			)
			(property "License" "Apache-2.0"
				(at 26.67 -21.59 0)
				(effects
					(font
						(size 1.27 1.27)
						(thickness 0.15)
					)
					(justify left bottom)
					(hide yes)
				)
			)
			(property "ki_keywords" "VERTICAL, THT, HEADER, CONNECTOR, MALE, WIRE-BOARD, POWER"
				(at 0 0 0)
				(effects
					(font
						(size 1.27 1.27)
					)
					(hide yes)
				)
			)
			(symbol "Molex_Mini-Fit-Jr_2x4_39-28-8080_1_1"
				(rectangle
					(start 2.54 1.27)
					(end 10.16 -8.89)
					(stroke
						(width 0.254)
						(type default)
					)
					(fill
						(type background)
					)
				)
				(rectangle
					(start 2.54 -3.175)
					(end 2.794 -4.445)
					(stroke
						(width 0.254)
						(type default)
					)
					(fill
						(type background)
					)
				)
				(pin passive line
					(at 0 0 0)
					(length 2.54)
					(name "5"
						(effects
							(font
								(size 1.27 1.27)
							)
						)
					)
					(number "5"
						(effects
							(font
								(size 1.27 1.27)
							)
						)
					)
				)
				(pin passive line
					(at 0 -2.54 0)
					(length 2.54)
					(name "6"
						(effects
							(font
								(size 1.27 1.27)
							)
						)
					)
					(number "6"
						(effects
							(font
								(size 1.27 1.27)
							)
						)
					)
				)
				(pin passive line
					(at 0 -5.08 0)
					(length 2.54)
					(name "7"
						(effects
							(font
								(size 1.27 1.27)
							)
						)
					)
					(number "7"
						(effects
							(font
								(size 1.27 1.27)
							)
						)
					)
				)
				(pin passive line
					(at 0 -7.62 0)
					(length 2.54)
					(name "8"
						(effects
							(font
								(size 1.27 1.27)
							)
						)
					)
					(number "8"
						(effects
							(font
								(size 1.27 1.27)
							)
						)
					)
				)
				(pin passive line
					(at 12.7 0 180)
					(length 2.54)
					(name "1"
						(effects
							(font
								(size 1.27 1.27)
							)
						)
					)
					(number "1"
						(effects
							(font
								(size 1.27 1.27)
							)
						)
					)
				)
				(pin passive line
					(at 12.7 -2.54 180)
					(length 2.54)
					(name "2"
						(effects
							(font
								(size 1.27 1.27)
							)
						)
					)
					(number "2"
						(effects
							(font
								(size 1.27 1.27)
							)
						)
					)
				)
				(pin passive line
					(at 12.7 -5.08 180)
					(length 2.54)
					(name "3"
						(effects
							(font
								(size 1.27 1.27)
							)
						)
					)
					(number "3"
						(effects
							(font
								(size 1.27 1.27)
							)
						)
					)
				)
				(pin passive line
					(at 12.7 -7.62 180)
					(length 2.54)
					(name "4"
						(effects
							(font
								(size 1.27 1.27)
							)
						)
					)
					(number "4"
						(effects
							(font
								(size 1.27 1.27)
							)
						)
					)
				)
			)
		)
	(symbol "antmicroWire2BoardConnectors:Molex_Nano-Fit_1x2_SMD_1054301202"
			(exclude_from_sim no)
			(in_bom yes)
			(on_board yes)
			(property "Reference" "J"
				(at 26.67 -2.54 0)
				(effects
					(font
						(size 1.27 1.27)
						(thickness 0.15)
					)
					(justify left bottom)
				)
			)
			(property "Value" "Molex_Nano-Fit_1x2_SMD_1054301202"
				(at 26.67 -7.62 0)
				(effects
					(font
						(size 1.27 1.27)
						(thickness 0.15)
					)
					(justify left bottom)
					(hide yes)
				)
			)
			(property "Footprint" "antmicro-footprints:Conn_Molex_Nano-Fit_1x2_SMD_1054301202"
				(at 26.67 -10.16 0)
				(effects
					(font
						(size 1.27 1.27)
						(thickness 0.15)
					)
					(justify left bottom)
					(hide yes)
				)
			)
			(property "Datasheet" "https://www.farnell.com/cad/3578051.pdf"
				(at 26.67 -12.7 0)
				(effects
					(font
						(size 1.27 1.27)
						(thickness 0.15)
					)
					(justify left bottom)
					(hide yes)
				)
			)
			(property "Description" "Pin Header, Pitch 2.5 mm, 1 Row, 2 Contacts, Nano-Fit"
				(at 0 0 0)
				(effects
					(font
						(size 1.27 1.27)
					)
					(hide yes)
				)
			)
			(property "Manufacturer" "Molex"
				(at 26.67 -15.24 0)
				(effects
					(font
						(size 1.27 1.27)
						(thickness 0.15)
					)
					(justify left bottom)
					(hide yes)
				)
			)
			(property "MPN" "105430-1202"
				(at 26.67 -5.08 0)
				(effects
					(font
						(size 1.27 1.27)
						(thickness 0.15)
					)
					(justify left bottom)
				)
			)
			(property "Author" "Antmicro"
				(at 26.67 -17.78 0)
				(effects
					(font
						(size 1.27 1.27)
						(thickness 0.15)
					)
					(justify left bottom)
					(hide yes)
				)
			)
			(property "License" "Apache-2.0"
				(at 26.67 -20.32 0)
				(effects
					(font
						(size 1.27 1.27)
						(thickness 0.15)
					)
					(justify left bottom)
					(hide yes)
				)
			)
			(property "ki_keywords" "CONNECTOR, HEADER, HORIZONTAL, SMT"
				(at 0 0 0)
				(effects
					(font
						(size 1.27 1.27)
					)
					(hide yes)
				)
			)
			(symbol "Molex_Nano-Fit_1x2_SMD_1054301202_1_1"
				(rectangle
					(start 2.54 2.54)
					(end 6.35 -7.62)
					(stroke
						(width 0.254)
						(type default)
					)
					(fill
						(type background)
					)
				)
				(rectangle
					(start 2.54 -0.254)
					(end 4.1402 0.381)
					(stroke
						(width 0.254)
						(type default)
					)
					(fill
						(type background)
					)
				)
				(rectangle
					(start 2.54 -2.794)
					(end 4.1402 -2.159)
					(stroke
						(width 0.254)
						(type default)
					)
					(fill
						(type background)
					)
				)
				(rectangle
					(start 2.54 -5.334)
					(end 4.1402 -4.699)
					(stroke
						(width 0.254)
						(type default)
					)
					(fill
						(type background)
					)
				)
				(pin passive line
					(at 0 0 0)
					(length 2.54)
					(name "~"
						(effects
							(font
								(size 1.27 1.27)
							)
						)
					)
					(number "1"
						(effects
							(font
								(size 1.27 1.27)
							)
						)
					)
				)
				(pin passive line
					(at 0 -2.54 0)
					(length 2.54)
					(name "~"
						(effects
							(font
								(size 1.27 1.27)
							)
						)
					)
					(number "2"
						(effects
							(font
								(size 1.27 1.27)
							)
						)
					)
				)
				(pin passive line
					(at 0 -5.08 0)
					(length 2.54)
					(name "~"
						(effects
							(font
								(size 1.27 1.27)
							)
						)
					)
					(number "MP"
						(effects
							(font
								(size 1.27 1.27)
							)
						)
					)
				)
			)
		)
	(symbol "antmicropower:+12V"
			(power)
			(pin_names
				(offset 0)
			)
			(exclude_from_sim no)
			(in_bom yes)
			(on_board yes)
			(property "Reference" "#PWR"
				(at 0 -3.81 0)
				(effects
					(font
						(size 1.27 1.27)
					)
					(hide yes)
				)
			)
			(property "Value" "+12V"
				(at 0 3.556 0)
				(effects
					(font
						(size 1.27 1.27)
					)
				)
			)
			(property "Footprint" ""
				(at 0 0 0)
				(effects
					(font
						(size 1.27 1.27)
					)
					(hide yes)
				)
			)
			(property "Datasheet" ""
				(at 0 0 0)
				(effects
					(font
						(size 1.27 1.27)
					)
					(hide yes)
				)
			)
			(property "Description" ""
				(at 0 0 0)
				(effects
					(font
						(size 1.27 1.27)
					)
					(hide yes)
				)
			)
			(symbol "+12V_0_1"
				(polyline
					(pts
						(xy -0.762 1.27) (xy 0 2.54)
					)
					(stroke
						(width 0)
						(type default)
					)
					(fill
						(type none)
					)
				)
				(polyline
					(pts
						(xy 0 2.54) (xy 0.762 1.27)
					)
					(stroke
						(width 0)
						(type default)
					)
					(fill
						(type none)
					)
				)
				(polyline
					(pts
						(xy 0 0) (xy 0 2.54)
					)
					(stroke
						(width 0)
						(type default)
					)
					(fill
						(type none)
					)
				)
			)
			(symbol "+12V_1_1"
				(pin power_in line
					(at 0 0 90)
					(length 0)
					(hide yes)
					(name "+12V"
						(effects
							(font
								(size 1.27 1.27)
							)
						)
					)
					(number "1"
						(effects
							(font
								(size 1.27 1.27)
							)
						)
					)
				)
			)
		)
	(symbol "antmicropower:+12V_AON"
			(power)
			(pin_names
				(offset 0)
			)
			(exclude_from_sim no)
			(in_bom yes)
			(on_board yes)
			(property "Reference" "#PWR"
				(at 0 -3.81 0)
				(effects
					(font
						(size 1.27 1.27)
					)
					(hide yes)
				)
			)
			(property "Value" "+12V_AON"
				(at 0 3.556 0)
				(effects
					(font
						(size 1.27 1.27)
					)
				)
			)
			(property "Footprint" ""
				(at 0 0 0)
				(effects
					(font
						(size 1.27 1.27)
					)
					(hide yes)
				)
			)
			(property "Datasheet" ""
				(at 0 0 0)
				(effects
					(font
						(size 1.27 1.27)
					)
					(hide yes)
				)
			)
			(property "Description" ""
				(at 0 0 0)
				(effects
					(font
						(size 1.27 1.27)
					)
					(hide yes)
				)
			)
			(symbol "+12V_AON_0_1"
				(polyline
					(pts
						(xy -0.762 1.27) (xy 0 2.54)
					)
					(stroke
						(width 0)
						(type default)
					)
					(fill
						(type none)
					)
				)
				(polyline
					(pts
						(xy 0 2.54) (xy 0.762 1.27)
					)
					(stroke
						(width 0)
						(type default)
					)
					(fill
						(type none)
					)
				)
				(polyline
					(pts
						(xy 0 0) (xy 0 2.54)
					)
					(stroke
						(width 0)
						(type default)
					)
					(fill
						(type none)
					)
				)
			)
			(symbol "+12V_AON_1_1"
				(pin power_in line
					(at 0 0 90)
					(length 0)
					(hide yes)
					(name "+12V_AON"
						(effects
							(font
								(size 1.27 1.27)
							)
						)
					)
					(number "1"
						(effects
							(font
								(size 1.27 1.27)
							)
						)
					)
				)
			)
		)
	(symbol "antmicropower:+3V3"
			(power)
			(pin_numbers
				(hide yes)
			)
			(pin_names
				(hide yes)
			)
			(exclude_from_sim no)
			(in_bom yes)
			(on_board yes)
			(property "Reference" "#PWR"
				(at 15.24 0 0)
				(effects
					(font
						(size 1.27 1.27)
						(thickness 0.15)
					)
					(justify left bottom)
					(hide yes)
				)
			)
			(property "Value" "+3V3"
				(at -3.175 2.54 0)
				(effects
					(font
						(size 1.27 1.27)
						(thickness 0.15)
					)
					(justify left bottom)
				)
			)
			(property "Footprint" ""
				(at 15.24 -7.62 0)
				(effects
					(font
						(size 1.27 1.27)
						(thickness 0.15)
					)
					(justify left bottom)
					(hide yes)
				)
			)
			(property "Datasheet" ""
				(at 15.24 -10.16 0)
				(effects
					(font
						(size 1.27 1.27)
						(thickness 0.15)
					)
					(justify left bottom)
					(hide yes)
				)
			)
			(property "Description" ""
				(at 0 0 0)
				(effects
					(font
						(size 1.27 1.27)
					)
					(hide yes)
				)
			)
			(property "Author" "Antmicro"
				(at 15.24 -2.54 0)
				(effects
					(font
						(size 1.27 1.27)
						(thickness 0.15)
					)
					(justify left bottom)
					(hide yes)
				)
			)
			(property "License" "Apache-2.0"
				(at 15.24 -5.08 0)
				(effects
					(font
						(size 1.27 1.27)
						(thickness 0.15)
					)
					(justify left bottom)
					(hide yes)
				)
			)
			(symbol "+3V3_0_1"
				(polyline
					(pts
						(xy 0 2.54) (xy -0.762 1.27)
					)
					(stroke
						(width 0)
						(type default)
					)
					(fill
						(type none)
					)
				)
				(polyline
					(pts
						(xy 0 2.54) (xy 0.762 1.27)
					)
					(stroke
						(width 0)
						(type default)
					)
					(fill
						(type none)
					)
				)
				(polyline
					(pts
						(xy 0 0) (xy 0 2.54)
					)
					(stroke
						(width 0)
						(type default)
					)
					(fill
						(type none)
					)
				)
			)
			(symbol "+3V3_1_1"
				(pin power_in line
					(at 0 0 90)
					(length 0)
					(hide yes)
					(name "+3V3"
						(effects
							(font
								(size 1.27 1.27)
							)
						)
					)
					(number "1"
						(effects
							(font
								(size 1.27 1.27)
							)
						)
					)
				)
			)
		)
	(symbol "antmicropower:GND"
			(power)
			(pin_numbers
				(hide yes)
			)
			(pin_names
				(hide yes)
			)
			(exclude_from_sim no)
			(in_bom yes)
			(on_board yes)
			(property "Reference" "#PWR"
				(at 8.89 -2.54 0)
				(effects
					(font
						(size 1.27 1.27)
						(thickness 0.15)
					)
					(justify left bottom)
					(hide yes)
				)
			)
			(property "Value" "GND"
				(at 8.89 -5.08 0)
				(effects
					(font
						(size 1.27 1.27)
						(thickness 0.15)
					)
					(justify left bottom)
				)
			)
			(property "Footprint" ""
				(at 8.89 -7.62 0)
				(effects
					(font
						(size 1.27 1.27)
						(thickness 0.15)
					)
					(justify left bottom)
					(hide yes)
				)
			)
			(property "Datasheet" ""
				(at 8.89 -12.7 0)
				(effects
					(font
						(size 1.27 1.27)
						(thickness 0.15)
					)
					(justify left bottom)
					(hide yes)
				)
			)
			(property "Description" ""
				(at 0 0 0)
				(effects
					(font
						(size 1.27 1.27)
					)
					(hide yes)
				)
			)
			(property "Author" "Antmicro"
				(at 8.89 -7.62 0)
				(effects
					(font
						(size 1.27 1.27)
						(thickness 0.15)
					)
					(justify left bottom)
					(hide yes)
				)
			)
			(property "License" "Apache-2.0"
				(at 8.89 -10.16 0)
				(effects
					(font
						(size 1.27 1.27)
						(thickness 0.15)
					)
					(justify left bottom)
					(hide yes)
				)
			)
			(symbol "GND_1_1"
				(polyline
					(pts
						(xy 0 0) (xy 0 -1.27) (xy 1.27 -1.27) (xy 0 -2.54) (xy -1.27 -1.27) (xy 0 -1.27)
					)
					(stroke
						(width 0)
						(type default)
					)
					(fill
						(type none)
					)
				)
				(pin power_in line
					(at 0 0 270)
					(length 0)
					(name "GND"
						(effects
							(font
								(size 1.27 1.27)
							)
						)
					)
					(number "1"
						(effects
							(font
								(size 1.27 1.27)
							)
						)
					)
				)
			)
		)
	(symbol "antmicropower:PWR_FLAG"
			(power)
			(pin_numbers
				(hide yes)
			)
			(pin_names
				(offset 0)
				(hide yes)
			)
			(exclude_from_sim no)
			(in_bom yes)
			(on_board yes)
			(property "Reference" "#FLG"
				(at 0 1.905 0)
				(effects
					(font
						(size 1.27 1.27)
					)
					(hide yes)
				)
			)
			(property "Value" "PWR_FLAG"
				(at 0 3.81 0)
				(effects
					(font
						(size 1.27 1.27)
					)
				)
			)
			(property "Footprint" ""
				(at 0 0 0)
				(effects
					(font
						(size 1.27 1.27)
					)
					(hide yes)
				)
			)
			(property "Datasheet" ""
				(at 0 0 0)
				(effects
					(font
						(size 1.27 1.27)
					)
					(hide yes)
				)
			)
			(property "Description" ""
				(at 0 0 0)
				(effects
					(font
						(size 1.27 1.27)
					)
					(hide yes)
				)
			)
			(symbol "PWR_FLAG_0_0"
				(pin power_out line
					(at 0 0 90)
					(length 0)
					(name "pwr"
						(effects
							(font
								(size 1.27 1.27)
							)
						)
					)
					(number "1"
						(effects
							(font
								(size 1.27 1.27)
							)
						)
					)
				)
			)
			(symbol "PWR_FLAG_0_1"
				(polyline
					(pts
						(xy 0 0) (xy 0 1.27) (xy -1.016 1.905) (xy 0 2.54) (xy 1.016 1.905) (xy 0 1.27)
					)
					(stroke
						(width 0)
						(type default)
					)
					(fill
						(type none)
					)
				)
			)
		)
	(symbol "antmicropower:VBUS"
			(power)
			(pin_names
				(offset 0)
			)
			(exclude_from_sim no)
			(in_bom yes)
			(on_board yes)
			(property "Reference" "#PWR"
				(at 0 -3.81 0)
				(effects
					(font
						(size 1.27 1.27)
					)
					(hide yes)
				)
			)
			(property "Value" "VBUS"
				(at 0 3.81 0)
				(effects
					(font
						(size 1.27 1.27)
					)
				)
			)
			(property "Footprint" ""
				(at 0 0 0)
				(effects
					(font
						(size 1.27 1.27)
					)
					(hide yes)
				)
			)
			(property "Datasheet" ""
				(at 0 0 0)
				(effects
					(font
						(size 1.27 1.27)
					)
					(hide yes)
				)
			)
			(property "Description" ""
				(at 0 0 0)
				(effects
					(font
						(size 1.27 1.27)
					)
					(hide yes)
				)
			)
			(symbol "VBUS_0_1"
				(polyline
					(pts
						(xy -0.762 1.27) (xy 0 2.54)
					)
					(stroke
						(width 0)
						(type default)
					)
					(fill
						(type none)
					)
				)
				(polyline
					(pts
						(xy 0 2.54) (xy 0.762 1.27)
					)
					(stroke
						(width 0)
						(type default)
					)
					(fill
						(type none)
					)
				)
				(polyline
					(pts
						(xy 0 0) (xy 0 2.54)
					)
					(stroke
						(width 0)
						(type default)
					)
					(fill
						(type none)
					)
				)
			)
			(symbol "VBUS_1_1"
				(pin power_in line
					(at 0 0 90)
					(length 0)
					(hide yes)
					(name "VBUS"
						(effects
							(font
								(size 1.27 1.27)
							)
						)
					)
					(number "1"
						(effects
							(font
								(size 1.27 1.27)
							)
						)
					)
				)
			)
		)
)
